FILE_TYPE = MACRO_DRAWING;
SET COLOR_WIRE YELLOW;
SET COLOR_PROP ORANGE;
SET COLOR_DOT WHITE;
SET COLOR_ARC YELLOW;
SET COLOR_BODY GREEN;
SET COLOR_NOTE PURPLE;
SET PROP_DISPLAY VALUE;
SET PAGE_NUMBER P45;
FORCEADD GENOA_SP5..9
(-4500 3575);
FORCEPROP 1 LAST LOCATION U26
J 0
(-5145 6406);
DISPLAY 0.489362 (-5145 6406);
PAINT SKYBLUE (-5145 6406);
FORCEPROP 0 LAST $SEC 9
J 0
(-5125 6450);
DISPLAY 0.680851 (-5125 6450);
PAINT MONO (-5125 6450);
DISPLAY INVISIBLE (-5125 6450);
FORCEPROP 0 LAST CDS_SEC 9
J 0
(-5125 6400);
DISPLAY 1.021277 (-5125 6400);
DISPLAY INVISIBLE (-5125 6400);
FORCEPROP 0 LASTPIN (-5300 2950) $PN BC19
J 2
(-5310 2960);
DISPLAY 0.489362 (-5310 2960);
PAINT MONO (-5310 2960);
FORCEPROP 0 LASTPIN (-5300 2900) $PN BD20
J 2
(-5310 2910);
DISPLAY 0.489362 (-5310 2910);
PAINT MONO (-5310 2910);
FORCEPROP 0 LASTPIN (-5300 1800) $PN BF20
J 2
(-5310 1810);
DISPLAY 0.489362 (-5310 1810);
PAINT MONO (-5310 1810);
FORCEPROP 0 LASTPIN (-5300 1750) $PN BG19
J 2
(-5310 1760);
DISPLAY 0.489362 (-5310 1760);
PAINT MONO (-5310 1760);
FORCEPROP 0 LASTPIN (-5300 2100) $PN AT21
J 2
(-5310 2110);
DISPLAY 0.489362 (-5310 2110);
PAINT MONO (-5310 2110);
FORCEPROP 0 LASTPIN (-5300 2000) $PN AU21
J 2
(-5310 2010);
DISPLAY 0.489362 (-5310 2010);
PAINT MONO (-5310 2010);
FORCEPROP 0 LASTPIN (-5300 2800) $PN AU19
J 2
(-5310 2810);
DISPLAY 0.489362 (-5310 2810);
PAINT MONO (-5310 2810);
FORCEPROP 0 LASTPIN (-5300 2750) $PN AV21
J 2
(-5310 2760);
DISPLAY 0.489362 (-5310 2760);
PAINT MONO (-5310 2760);
FORCEPROP 0 LASTPIN (-5300 2650) $PN BN21
J 2
(-5310 2660);
DISPLAY 0.489362 (-5310 2660);
PAINT MONO (-5310 2660);
FORCEPROP 0 LASTPIN (-5300 1650) $PN AV20
J 2
(-5310 1660);
DISPLAY 0.489362 (-5310 1660);
PAINT MONO (-5310 1660);
FORCEPROP 0 LASTPIN (-5300 1600) $PN AW21
J 2
(-5310 1610);
DISPLAY 0.489362 (-5310 1610);
PAINT MONO (-5310 1610);
FORCEPROP 0 LASTPIN (-5300 1500) $PN BP21
J 2
(-5310 1510);
DISPLAY 0.489362 (-5310 1510);
PAINT MONO (-5310 1510);
FORCEPROP 0 LASTPIN (-5300 3800) $PN AW19
J 2
(-5310 3810);
DISPLAY 0.489362 (-5310 3810);
PAINT MONO (-5310 3810);
FORCEPROP 0 LASTPIN (-5300 3750) $PN AY20
J 2
(-5310 3760);
DISPLAY 0.489362 (-5310 3760);
PAINT MONO (-5310 3760);
FORCEPROP 0 LASTPIN (-5300 3700) $PN AY21
J 2
(-5310 3710);
DISPLAY 0.489362 (-5310 3710);
PAINT MONO (-5310 3710);
FORCEPROP 0 LASTPIN (-5300 3650) $PN BA21
J 2
(-5310 3660);
DISPLAY 0.489362 (-5310 3660);
PAINT MONO (-5310 3660);
FORCEPROP 0 LASTPIN (-5300 3600) $PN BA19
J 2
(-5310 3610);
DISPLAY 0.489362 (-5310 3610);
PAINT MONO (-5310 3610);
FORCEPROP 0 LASTPIN (-5300 3550) $PN BB20
J 2
(-5310 3560);
DISPLAY 0.489362 (-5310 3560);
PAINT MONO (-5310 3560);
FORCEPROP 0 LASTPIN (-5300 3500) $PN BB21
J 2
(-5310 3510);
DISPLAY 0.489362 (-5310 3510);
PAINT MONO (-5310 3510);
FORCEPROP 0 LASTPIN (-3700 2350) $PN AJ19
J 0
(-3690 2360);
DISPLAY 0.489362 (-3690 2360);
PAINT MONO (-3690 2360);
FORCEPROP 0 LASTPIN (-3700 2300) $PN AK21
J 0
(-3690 2310);
DISPLAY 0.489362 (-3690 2310);
PAINT MONO (-3690 2310);
FORCEPROP 0 LASTPIN (-3700 2250) $PN AK20
J 0
(-3690 2260);
DISPLAY 0.489362 (-3690 2260);
PAINT MONO (-3690 2260);
FORCEPROP 0 LASTPIN (-3700 2200) $PN AL21
J 0
(-3690 2210);
DISPLAY 0.489362 (-3690 2210);
PAINT MONO (-3690 2210);
FORCEPROP 0 LASTPIN (-3700 2150) $PN AN19
J 0
(-3690 2160);
DISPLAY 0.489362 (-3690 2160);
PAINT MONO (-3690 2160);
FORCEPROP 0 LASTPIN (-3700 2100) $PN AP21
J 0
(-3690 2110);
DISPLAY 0.489362 (-3690 2110);
PAINT MONO (-3690 2110);
FORCEPROP 0 LASTPIN (-3700 2050) $PN AP20
J 0
(-3690 2060);
DISPLAY 0.489362 (-3690 2060);
PAINT MONO (-3690 2060);
FORCEPROP 0 LASTPIN (-3700 2000) $PN AR21
J 0
(-3690 2010);
DISPLAY 0.489362 (-3690 2010);
PAINT MONO (-3690 2010);
FORCEPROP 0 LASTPIN (-3700 5950) $PN E19
J 0
(-3690 5960);
DISPLAY 0.489362 (-3690 5960);
PAINT MONO (-3690 5960);
FORCEPROP 0 LASTPIN (-3700 5900) $PN F21
J 0
(-3690 5910);
DISPLAY 0.489362 (-3690 5910);
PAINT MONO (-3690 5910);
FORCEPROP 0 LASTPIN (-3700 5850) $PN F20
J 0
(-3690 5860);
DISPLAY 0.489362 (-3690 5860);
PAINT MONO (-3690 5860);
FORCEPROP 0 LASTPIN (-3700 5800) $PN G21
J 0
(-3690 5810);
DISPLAY 0.489362 (-3690 5810);
PAINT MONO (-3690 5810);
FORCEPROP 0 LASTPIN (-3700 5750) $PN J19
J 0
(-3690 5760);
DISPLAY 0.489362 (-3690 5760);
PAINT MONO (-3690 5760);
FORCEPROP 0 LASTPIN (-3700 5700) $PN K21
J 0
(-3690 5710);
DISPLAY 0.489362 (-3690 5710);
PAINT MONO (-3690 5710);
FORCEPROP 0 LASTPIN (-3700 5650) $PN K20
J 0
(-3690 5660);
DISPLAY 0.489362 (-3690 5660);
PAINT MONO (-3690 5660);
FORCEPROP 0 LASTPIN (-3700 5600) $PN L21
J 0
(-3690 5610);
DISPLAY 0.489362 (-3690 5610);
PAINT MONO (-3690 5610);
FORCEPROP 0 LASTPIN (-3700 5500) $PN L19
J 0
(-3690 5510);
DISPLAY 0.489362 (-3690 5510);
PAINT MONO (-3690 5510);
FORCEPROP 0 LASTPIN (-3700 5450) $PN M21
J 0
(-3690 5460);
DISPLAY 0.489362 (-3690 5460);
PAINT MONO (-3690 5460);
FORCEPROP 0 LASTPIN (-3700 5400) $PN M20
J 0
(-3690 5410);
DISPLAY 0.489362 (-3690 5410);
PAINT MONO (-3690 5410);
FORCEPROP 0 LASTPIN (-3700 5350) $PN N21
J 0
(-3690 5360);
DISPLAY 0.489362 (-3690 5360);
PAINT MONO (-3690 5360);
FORCEPROP 0 LASTPIN (-3700 5300) $PN R19
J 0
(-3690 5310);
DISPLAY 0.489362 (-3690 5310);
PAINT MONO (-3690 5310);
FORCEPROP 0 LASTPIN (-3700 5250) $PN T21
J 0
(-3690 5260);
DISPLAY 0.489362 (-3690 5260);
PAINT MONO (-3690 5260);
FORCEPROP 0 LASTPIN (-3700 5200) $PN T20
J 0
(-3690 5210);
DISPLAY 0.489362 (-3690 5210);
PAINT MONO (-3690 5210);
FORCEPROP 0 LASTPIN (-3700 5150) $PN U21
J 0
(-3690 5160);
DISPLAY 0.489362 (-3690 5160);
PAINT MONO (-3690 5160);
FORCEPROP 0 LASTPIN (-3700 5050) $PN U19
J 0
(-3690 5060);
DISPLAY 0.489362 (-3690 5060);
PAINT MONO (-3690 5060);
FORCEPROP 0 LASTPIN (-3700 5000) $PN V21
J 0
(-3690 5010);
DISPLAY 0.489362 (-3690 5010);
PAINT MONO (-3690 5010);
FORCEPROP 0 LASTPIN (-3700 4950) $PN V20
J 0
(-3690 4960);
DISPLAY 0.489362 (-3690 4960);
PAINT MONO (-3690 4960);
FORCEPROP 0 LASTPIN (-3700 4900) $PN W21
J 0
(-3690 4910);
DISPLAY 0.489362 (-3690 4910);
PAINT MONO (-3690 4910);
FORCEPROP 0 LASTPIN (-3700 4850) $PN AA19
J 0
(-3690 4860);
DISPLAY 0.489362 (-3690 4860);
PAINT MONO (-3690 4860);
FORCEPROP 0 LASTPIN (-3700 4800) $PN AB21
J 0
(-3690 4810);
DISPLAY 0.489362 (-3690 4810);
PAINT MONO (-3690 4810);
FORCEPROP 0 LASTPIN (-3700 4750) $PN AB20
J 0
(-3690 4760);
DISPLAY 0.489362 (-3690 4760);
PAINT MONO (-3690 4760);
FORCEPROP 0 LASTPIN (-3700 4700) $PN AC21
J 0
(-3690 4710);
DISPLAY 0.489362 (-3690 4710);
PAINT MONO (-3690 4710);
FORCEPROP 0 LASTPIN (-3700 4600) $PN AC19
J 0
(-3690 4610);
DISPLAY 0.489362 (-3690 4610);
PAINT MONO (-3690 4610);
FORCEPROP 0 LASTPIN (-3700 4550) $PN AD21
J 0
(-3690 4560);
DISPLAY 0.489362 (-3690 4560);
PAINT MONO (-3690 4560);
FORCEPROP 0 LASTPIN (-3700 4500) $PN AD20
J 0
(-3690 4510);
DISPLAY 0.489362 (-3690 4510);
PAINT MONO (-3690 4510);
FORCEPROP 0 LASTPIN (-3700 4450) $PN AE21
J 0
(-3690 4460);
DISPLAY 0.489362 (-3690 4460);
PAINT MONO (-3690 4460);
FORCEPROP 0 LASTPIN (-3700 4400) $PN AG19
J 0
(-3690 4410);
DISPLAY 0.489362 (-3690 4410);
PAINT MONO (-3690 4410);
FORCEPROP 0 LASTPIN (-3700 4350) $PN AH21
J 0
(-3690 4360);
DISPLAY 0.489362 (-3690 4360);
PAINT MONO (-3690 4360);
FORCEPROP 0 LASTPIN (-3700 4300) $PN AH20
J 0
(-3690 4310);
DISPLAY 0.489362 (-3690 4310);
PAINT MONO (-3690 4310);
FORCEPROP 0 LASTPIN (-3700 4250) $PN AJ21
J 0
(-3690 4260);
DISPLAY 0.489362 (-3690 4260);
PAINT MONO (-3690 4260);
FORCEPROP 0 LASTPIN (-5300 5950) $PN G19
J 2
(-5310 5960);
DISPLAY 0.489362 (-5310 5960);
PAINT MONO (-5310 5960);
FORCEPROP 0 LASTPIN (-5300 5850) $PN N19
J 2
(-5310 5860);
DISPLAY 0.489362 (-5310 5860);
PAINT MONO (-5310 5860);
FORCEPROP 0 LASTPIN (-5300 5750) $PN W19
J 2
(-5310 5760);
DISPLAY 0.489362 (-5310 5760);
PAINT MONO (-5310 5760);
FORCEPROP 0 LASTPIN (-5300 5650) $PN AE19
J 2
(-5310 5660);
DISPLAY 0.489362 (-5310 5660);
PAINT MONO (-5310 5660);
FORCEPROP 0 LASTPIN (-5300 5550) $PN AL19
J 2
(-5310 5560);
DISPLAY 0.489362 (-5310 5560);
PAINT MONO (-5310 5560);
FORCEPROP 0 LASTPIN (-5300 5450) $PN J21
J 2
(-5310 5460);
DISPLAY 0.489362 (-5310 5460);
PAINT MONO (-5310 5460);
FORCEPROP 0 LASTPIN (-5300 5350) $PN R21
J 2
(-5310 5360);
DISPLAY 0.489362 (-5310 5360);
PAINT MONO (-5310 5360);
FORCEPROP 0 LASTPIN (-5300 5250) $PN AA21
J 2
(-5310 5260);
DISPLAY 0.489362 (-5310 5260);
PAINT MONO (-5310 5260);
FORCEPROP 0 LASTPIN (-5300 5150) $PN AG21
J 2
(-5310 5160);
DISPLAY 0.489362 (-5310 5160);
PAINT MONO (-5310 5160);
FORCEPROP 0 LASTPIN (-5300 5050) $PN AN21
J 2
(-5310 5060);
DISPLAY 0.489362 (-5310 5060);
PAINT MONO (-5310 5060);
FORCEPROP 0 LASTPIN (-5300 5900) $PN H20
J 2
(-5310 5910);
DISPLAY 0.489362 (-5310 5910);
PAINT MONO (-5310 5910);
FORCEPROP 0 LASTPIN (-5300 5800) $PN P20
J 2
(-5310 5810);
DISPLAY 0.489362 (-5310 5810);
PAINT MONO (-5310 5810);
FORCEPROP 0 LASTPIN (-5300 5700) $PN Y20
J 2
(-5310 5710);
DISPLAY 0.489362 (-5310 5710);
PAINT MONO (-5310 5710);
FORCEPROP 0 LASTPIN (-5300 5600) $PN AF20
J 2
(-5310 5610);
DISPLAY 0.489362 (-5310 5610);
PAINT MONO (-5310 5610);
FORCEPROP 0 LASTPIN (-5300 5500) $PN AM20
J 2
(-5310 5510);
DISPLAY 0.489362 (-5310 5510);
PAINT MONO (-5310 5510);
FORCEPROP 0 LASTPIN (-5300 5400) $PN H21
J 2
(-5310 5410);
DISPLAY 0.489362 (-5310 5410);
PAINT MONO (-5310 5410);
FORCEPROP 0 LASTPIN (-5300 5300) $PN P21
J 2
(-5310 5310);
DISPLAY 0.489362 (-5310 5310);
PAINT MONO (-5310 5310);
FORCEPROP 0 LASTPIN (-5300 5200) $PN Y21
J 2
(-5310 5210);
DISPLAY 0.489362 (-5310 5210);
PAINT MONO (-5310 5210);
FORCEPROP 0 LASTPIN (-5300 5100) $PN AF21
J 2
(-5310 5110);
DISPLAY 0.489362 (-5310 5110);
PAINT MONO (-5310 5110);
FORCEPROP 0 LASTPIN (-5300 5000) $PN AM21
J 2
(-5310 5010);
DISPLAY 0.489362 (-5310 5010);
PAINT MONO (-5310 5010);
FORCEPROP 0 LASTPIN (-5300 2550) $PN BC21
J 2
(-5310 2560);
DISPLAY 0.489362 (-5310 2560);
PAINT MONO (-5310 2560);
FORCEPROP 0 LASTPIN (-5300 2450) $PN BM21
J 2
(-5310 2460);
DISPLAY 0.489362 (-5310 2460);
PAINT MONO (-5310 2460);
FORCEPROP 0 LASTPIN (-5300 2400) $PN BN19
J 2
(-5310 2410);
DISPLAY 0.489362 (-5310 2410);
PAINT MONO (-5310 2410);
FORCEPROP 0 LASTPIN (-5300 2300) $PN BP20
J 2
(-5310 2310);
DISPLAY 0.489362 (-5310 2310);
PAINT MONO (-5310 2310);
FORCEPROP 0 LASTPIN (-5300 1400) $PN BL19
J 2
(-5310 1410);
DISPLAY 0.489362 (-5310 1410);
PAINT MONO (-5310 1410);
FORCEPROP 0 LASTPIN (-5300 1350) $PN BM20
J 2
(-5310 1360);
DISPLAY 0.489362 (-5310 1360);
PAINT MONO (-5310 1360);
FORCEPROP 0 LASTPIN (-5300 1250) $PN BR19
J 2
(-5310 1260);
DISPLAY 0.489362 (-5310 1260);
PAINT MONO (-5310 1260);
FORCEPROP 0 LASTPIN (-5300 3400) $PN BG21
J 2
(-5310 3410);
DISPLAY 0.489362 (-5310 3410);
PAINT MONO (-5310 3410);
FORCEPROP 0 LASTPIN (-5300 3350) $PN BH21
J 2
(-5310 3360);
DISPLAY 0.489362 (-5310 3360);
PAINT MONO (-5310 3360);
FORCEPROP 0 LASTPIN (-5300 3300) $PN BH20
J 2
(-5310 3310);
DISPLAY 0.489362 (-5310 3310);
PAINT MONO (-5310 3310);
FORCEPROP 0 LASTPIN (-5300 3250) $PN BJ19
J 2
(-5310 3260);
DISPLAY 0.489362 (-5310 3260);
PAINT MONO (-5310 3260);
FORCEPROP 0 LASTPIN (-5300 3200) $PN BJ21
J 2
(-5310 3210);
DISPLAY 0.489362 (-5310 3210);
PAINT MONO (-5310 3210);
FORCEPROP 0 LASTPIN (-5300 3150) $PN BK21
J 2
(-5310 3160);
DISPLAY 0.489362 (-5310 3160);
PAINT MONO (-5310 3160);
FORCEPROP 0 LASTPIN (-5300 3100) $PN BK20
J 2
(-5310 3110);
DISPLAY 0.489362 (-5310 3110);
PAINT MONO (-5310 3110);
FORCEPROP 0 LASTPIN (-3700 1900) $PN BY20
J 0
(-3690 1910);
DISPLAY 0.489362 (-3690 1910);
PAINT MONO (-3690 1910);
FORCEPROP 0 LASTPIN (-3700 1850) $PN CA21
J 0
(-3690 1860);
DISPLAY 0.489362 (-3690 1860);
PAINT MONO (-3690 1860);
FORCEPROP 0 LASTPIN (-3700 1800) $PN CA19
J 0
(-3690 1810);
DISPLAY 0.489362 (-3690 1810);
PAINT MONO (-3690 1810);
FORCEPROP 0 LASTPIN (-3700 1750) $PN CB21
J 0
(-3690 1760);
DISPLAY 0.489362 (-3690 1760);
PAINT MONO (-3690 1760);
FORCEPROP 0 LASTPIN (-3700 1700) $PN BT20
J 0
(-3690 1710);
DISPLAY 0.489362 (-3690 1710);
PAINT MONO (-3690 1710);
FORCEPROP 0 LASTPIN (-3700 1650) $PN BU21
J 0
(-3690 1660);
DISPLAY 0.489362 (-3690 1660);
PAINT MONO (-3690 1660);
FORCEPROP 0 LASTPIN (-3700 1600) $PN BU19
J 0
(-3690 1610);
DISPLAY 0.489362 (-3690 1610);
PAINT MONO (-3690 1610);
FORCEPROP 0 LASTPIN (-3700 1550) $PN BV21
J 0
(-3690 1560);
DISPLAY 0.489362 (-3690 1560);
PAINT MONO (-3690 1560);
FORCEPROP 0 LASTPIN (-3700 4150) $PN CB20
J 0
(-3690 4160);
DISPLAY 0.489362 (-3690 4160);
PAINT MONO (-3690 4160);
FORCEPROP 0 LASTPIN (-3700 4100) $PN CC21
J 0
(-3690 4110);
DISPLAY 0.489362 (-3690 4110);
PAINT MONO (-3690 4110);
FORCEPROP 0 LASTPIN (-3700 4050) $PN CC19
J 0
(-3690 4060);
DISPLAY 0.489362 (-3690 4060);
PAINT MONO (-3690 4060);
FORCEPROP 0 LASTPIN (-3700 4000) $PN CD21
J 0
(-3690 4010);
DISPLAY 0.489362 (-3690 4010);
PAINT MONO (-3690 4010);
FORCEPROP 0 LASTPIN (-3700 3950) $PN CF20
J 0
(-3690 3960);
DISPLAY 0.489362 (-3690 3960);
PAINT MONO (-3690 3960);
FORCEPROP 0 LASTPIN (-3700 3900) $PN CG21
J 0
(-3690 3910);
DISPLAY 0.489362 (-3690 3910);
PAINT MONO (-3690 3910);
FORCEPROP 0 LASTPIN (-3700 3850) $PN CG19
J 0
(-3690 3860);
DISPLAY 0.489362 (-3690 3860);
PAINT MONO (-3690 3860);
FORCEPROP 0 LASTPIN (-3700 3800) $PN CH21
J 0
(-3690 3810);
DISPLAY 0.489362 (-3690 3810);
PAINT MONO (-3690 3810);
FORCEPROP 0 LASTPIN (-3700 3700) $PN CH20
J 0
(-3690 3710);
DISPLAY 0.489362 (-3690 3710);
PAINT MONO (-3690 3710);
FORCEPROP 0 LASTPIN (-3700 3650) $PN CJ21
J 0
(-3690 3660);
DISPLAY 0.489362 (-3690 3660);
PAINT MONO (-3690 3660);
FORCEPROP 0 LASTPIN (-3700 3600) $PN CJ19
J 0
(-3690 3610);
DISPLAY 0.489362 (-3690 3610);
PAINT MONO (-3690 3610);
FORCEPROP 0 LASTPIN (-3700 3550) $PN CK21
J 0
(-3690 3560);
DISPLAY 0.489362 (-3690 3560);
PAINT MONO (-3690 3560);
FORCEPROP 0 LASTPIN (-3700 3500) $PN CM20
J 0
(-3690 3510);
DISPLAY 0.489362 (-3690 3510);
PAINT MONO (-3690 3510);
FORCEPROP 0 LASTPIN (-3700 3450) $PN CN21
J 0
(-3690 3460);
DISPLAY 0.489362 (-3690 3460);
PAINT MONO (-3690 3460);
FORCEPROP 0 LASTPIN (-3700 3400) $PN CN19
J 0
(-3690 3410);
DISPLAY 0.489362 (-3690 3410);
PAINT MONO (-3690 3410);
FORCEPROP 0 LASTPIN (-3700 3350) $PN CP21
J 0
(-3690 3360);
DISPLAY 0.489362 (-3690 3360);
PAINT MONO (-3690 3360);
FORCEPROP 0 LASTPIN (-3700 3250) $PN CP20
J 0
(-3690 3260);
DISPLAY 0.489362 (-3690 3260);
PAINT MONO (-3690 3260);
FORCEPROP 0 LASTPIN (-3700 3200) $PN CR21
J 0
(-3690 3210);
DISPLAY 0.489362 (-3690 3210);
PAINT MONO (-3690 3210);
FORCEPROP 0 LASTPIN (-3700 3150) $PN CR19
J 0
(-3690 3160);
DISPLAY 0.489362 (-3690 3160);
PAINT MONO (-3690 3160);
FORCEPROP 0 LASTPIN (-3700 3100) $PN CT21
J 0
(-3690 3110);
DISPLAY 0.489362 (-3690 3110);
PAINT MONO (-3690 3110);
FORCEPROP 0 LASTPIN (-3700 3050) $PN CV20
J 0
(-3690 3060);
DISPLAY 0.489362 (-3690 3060);
PAINT MONO (-3690 3060);
FORCEPROP 0 LASTPIN (-3700 3000) $PN CW21
J 0
(-3690 3010);
DISPLAY 0.489362 (-3690 3010);
PAINT MONO (-3690 3010);
FORCEPROP 0 LASTPIN (-3700 2950) $PN CW19
J 0
(-3690 2960);
DISPLAY 0.489362 (-3690 2960);
PAINT MONO (-3690 2960);
FORCEPROP 0 LASTPIN (-3700 2900) $PN CY21
J 0
(-3690 2910);
DISPLAY 0.489362 (-3690 2910);
PAINT MONO (-3690 2910);
FORCEPROP 0 LASTPIN (-3700 2800) $PN CY20
J 0
(-3690 2810);
DISPLAY 0.489362 (-3690 2810);
PAINT MONO (-3690 2810);
FORCEPROP 0 LASTPIN (-3700 2750) $PN DA21
J 0
(-3690 2760);
DISPLAY 0.489362 (-3690 2760);
PAINT MONO (-3690 2760);
FORCEPROP 0 LASTPIN (-3700 2700) $PN DA19
J 0
(-3690 2710);
DISPLAY 0.489362 (-3690 2710);
PAINT MONO (-3690 2710);
FORCEPROP 0 LASTPIN (-3700 2650) $PN DB21
J 0
(-3690 2660);
DISPLAY 0.489362 (-3690 2660);
PAINT MONO (-3690 2660);
FORCEPROP 0 LASTPIN (-3700 2600) $PN DD20
J 0
(-3690 2610);
DISPLAY 0.489362 (-3690 2610);
PAINT MONO (-3690 2610);
FORCEPROP 0 LASTPIN (-3700 2550) $PN DE21
J 0
(-3690 2560);
DISPLAY 0.489362 (-3690 2560);
PAINT MONO (-3690 2560);
FORCEPROP 0 LASTPIN (-3700 2500) $PN DE19
J 0
(-3690 2510);
DISPLAY 0.489362 (-3690 2510);
PAINT MONO (-3690 2510);
FORCEPROP 0 LASTPIN (-3700 2450) $PN DF21
J 0
(-3690 2460);
DISPLAY 0.489362 (-3690 2460);
PAINT MONO (-3690 2460);
FORCEPROP 0 LASTPIN (-5300 4900) $PN CD20
J 2
(-5310 4910);
DISPLAY 0.489362 (-5310 4910);
PAINT MONO (-5310 4910);
FORCEPROP 0 LASTPIN (-5300 4800) $PN CK20
J 2
(-5310 4810);
DISPLAY 0.489362 (-5310 4810);
PAINT MONO (-5310 4810);
FORCEPROP 0 LASTPIN (-5300 4700) $PN CT20
J 2
(-5310 4710);
DISPLAY 0.489362 (-5310 4710);
PAINT MONO (-5310 4710);
FORCEPROP 0 LASTPIN (-5300 4600) $PN DB20
J 2
(-5310 4610);
DISPLAY 0.489362 (-5310 4610);
PAINT MONO (-5310 4610);
FORCEPROP 0 LASTPIN (-5300 4500) $PN BY21
J 2
(-5310 4510);
DISPLAY 0.489362 (-5310 4510);
PAINT MONO (-5310 4510);
FORCEPROP 0 LASTPIN (-5300 4400) $PN CF21
J 2
(-5310 4410);
DISPLAY 0.489362 (-5310 4410);
PAINT MONO (-5310 4410);
FORCEPROP 0 LASTPIN (-5300 4300) $PN CM21
J 2
(-5310 4310);
DISPLAY 0.489362 (-5310 4310);
PAINT MONO (-5310 4310);
FORCEPROP 0 LASTPIN (-5300 4200) $PN CV21
J 2
(-5310 4210);
DISPLAY 0.489362 (-5310 4210);
PAINT MONO (-5310 4210);
FORCEPROP 0 LASTPIN (-5300 4100) $PN DD21
J 2
(-5310 4110);
DISPLAY 0.489362 (-5310 4110);
PAINT MONO (-5310 4110);
FORCEPROP 0 LASTPIN (-5300 4000) $PN BV20
J 2
(-5310 4010);
DISPLAY 0.489362 (-5310 4010);
PAINT MONO (-5310 4010);
FORCEPROP 0 LASTPIN (-5300 4850) $PN CE19
J 2
(-5310 4860);
DISPLAY 0.489362 (-5310 4860);
PAINT MONO (-5310 4860);
FORCEPROP 0 LASTPIN (-5300 4750) $PN CL19
J 2
(-5310 4760);
DISPLAY 0.489362 (-5310 4760);
PAINT MONO (-5310 4760);
FORCEPROP 0 LASTPIN (-5300 4650) $PN CU19
J 2
(-5310 4660);
DISPLAY 0.489362 (-5310 4660);
PAINT MONO (-5310 4660);
FORCEPROP 0 LASTPIN (-5300 4550) $PN DC19
J 2
(-5310 4560);
DISPLAY 0.489362 (-5310 4560);
PAINT MONO (-5310 4560);
FORCEPROP 0 LASTPIN (-5300 4450) $PN BW21
J 2
(-5310 4460);
DISPLAY 0.489362 (-5310 4460);
PAINT MONO (-5310 4460);
FORCEPROP 0 LASTPIN (-5300 4350) $PN CE21
J 2
(-5310 4360);
DISPLAY 0.489362 (-5310 4360);
PAINT MONO (-5310 4360);
FORCEPROP 0 LASTPIN (-5300 4250) $PN CL21
J 2
(-5310 4260);
DISPLAY 0.489362 (-5310 4260);
PAINT MONO (-5310 4260);
FORCEPROP 0 LASTPIN (-5300 4150) $PN CU21
J 2
(-5310 4160);
DISPLAY 0.489362 (-5310 4160);
PAINT MONO (-5310 4160);
FORCEPROP 0 LASTPIN (-5300 4050) $PN DC21
J 2
(-5310 4060);
DISPLAY 0.489362 (-5310 4060);
PAINT MONO (-5310 4060);
FORCEPROP 0 LASTPIN (-5300 3950) $PN BW19
J 2
(-5310 3960);
DISPLAY 0.489362 (-5310 3960);
PAINT MONO (-5310 3960);
FORCEPROP 0 LASTPIN (-5300 2200) $PN BL21
J 2
(-5310 2210);
DISPLAY 0.489362 (-5310 2210);
PAINT MONO (-5310 2210);
FORCEPROP 0 LASTPIN (-5300 1150) $PN BF21
J 2
(-5310 1160);
DISPLAY 0.489362 (-5310 1160);
PAINT MONO (-5310 1160);
FORCEPROP 2 LAST PART_TYPE SMLF
J 0
(-5125 6350);
DISPLAY 1.021277 (-5125 6350);
FORCEPROP 1 LAST MATERIAL IO
J 0
(-5145 6132);
DISPLAY 0.489362 (-5145 6132);
PAINT SKYBLUE (-5145 6132);
FORCEPROP 2 LAST VALUE SOCKET6096_13568-001
J 0
(-5125 6250);
DISPLAY 0.489362 (-5125 6250);
PAINT SKYBLUE (-5125 6250);
FORCEPROP 1 LAST NEEDS_NO_SIZE TRUE
J 0
(-4500 3575);
DISPLAY 0.723404 (-4500 3575);
PAINT GREEN (-4500 3575);
DISPLAY INVISIBLE (-4500 3575);
FORCEPROP 1 LAST CDS_LMAN_SYM_OUTLINE -650,2525,650,-2525
J 0
(-4500 3575);
DISPLAY 0.468085 (-4500 3575);
PAINT GREEN (-4500 3575);
DISPLAY INVISIBLE (-4500 3575);
FORCEPROP 2 LAST CDS_LIB pure_quanta
J 0
(-4500 3575);
DISPLAY INVISIBLE (-4500 3575);
FORCEPROP 1 LAST PATH I159
J 0
(-4500 3575);
DISPLAY 0.723404 (-4500 3575);
PAINT GREEN (-4500 3575);
DISPLAY INVISIBLE (-4500 3575);
FORCEPROP 1 LAST PART_NUMBER DGA^6000030
J 0
(-5145 6259);
DISPLAY 0.489362 (-5145 6259);
PAINT SKYBLUE (-5145 6259);
DISPLAY INVISIBLE (-5145 6259);
FORCEADD OFFPAGE..3
(-2500 5975);
FORCEPROP 2 LAST $XR0 106 
J 0
(-2286 5975);
DISPLAY 0.638298 (-2286 5975);
PAINT MONO (-2286 5975);
FORCEPROP 2 LAST CDS_LIB mstr_standard
J 0
(-2500 5975);
DISPLAY 0.723404 (-2500 5975);
PAINT MONO (-2500 5975);
DISPLAY INVISIBLE (-2500 5975);
FORCEPROP 1 LAST OFFPAGE TRUE
J 0
(-2175 5850);
DISPLAY 0.872340 (-2175 5850);
PAINT GREEN (-2175 5850);
DISPLAY INVISIBLE (-2175 5850);
FORCEPROP 1 LAST COMMENT_BODY TRUE
J 0
(-2550 5875);
DISPLAY 0.872340 (-2550 5875);
PAINT GREEN (-2550 5875);
DISPLAY INVISIBLE (-2550 5875);
FORCEPROP 2 LAST PATH I160
J 0
(-2275 6025);
DISPLAY 1.021277 (-2275 6025);
DISPLAY INVISIBLE (-2275 6025);
FORCEADD OFFPAGE..3
(-2500 4175);
FORCEPROP 2 LAST $XR0 106 
J 0
(-2286 4175);
DISPLAY 0.638298 (-2286 4175);
PAINT MONO (-2286 4175);
FORCEPROP 2 LAST CDS_LIB mstr_standard
J 0
(-2500 4175);
DISPLAY 0.723404 (-2500 4175);
PAINT MONO (-2500 4175);
DISPLAY INVISIBLE (-2500 4175);
FORCEPROP 1 LAST OFFPAGE TRUE
J 0
(-2175 4050);
DISPLAY 0.872340 (-2175 4050);
PAINT GREEN (-2175 4050);
DISPLAY INVISIBLE (-2175 4050);
FORCEPROP 1 LAST COMMENT_BODY TRUE
J 0
(-2550 4075);
DISPLAY 0.872340 (-2550 4075);
PAINT GREEN (-2550 4075);
DISPLAY INVISIBLE (-2550 4075);
FORCEPROP 2 LAST PATH I161
J 0
(-2275 4225);
DISPLAY 1.021277 (-2275 4225);
DISPLAY INVISIBLE (-2275 4225);
FORCEADD TAP..1
(-3225 5900);
FORCEPROP 3 LASTPIN (-3275 5900) SIG_NAME M_I_CPU1_SA_DQ<1>
J 0
(-3265 5910);
DISPLAY 0.659574 (-3265 5910);
PAINT MONO (-3265 5910);
DISPLAY INVISIBLE (-3265 5910);
FORCEPROP 1 LASTPIN (-3275 5900) BN 1
J 0
(-3287 5908);
DISPLAY 0.489362 (-3287 5908);
PAINT GREEN (-3287 5908);
FORCEPROP 2 LAST CDS_LIB mstr_standard
J 0
(-3225 5900);
DISPLAY 0.723404 (-3225 5900);
PAINT MONO (-3225 5900);
DISPLAY INVISIBLE (-3225 5900);
FORCEPROP 1 LAST BODY_TYPE PLUMBING
J 0
(-3225 5950);
DISPLAY 0.872340 (-3225 5950);
PAINT GREEN (-3225 5950);
DISPLAY INVISIBLE (-3225 5950);
FORCEPROP 1 LAST HDL_TAP TRUE
J 0
(-2900 5775);
DISPLAY 0.872340 (-2900 5775);
DISPLAY INVISIBLE (-2900 5775);
FORCEPROP 1 LAST PATH I162
J 0
(-3227 5900);
DISPLAY 0.872340 (-3227 5900);
PAINT GREEN (-3227 5900);
DISPLAY INVISIBLE (-3227 5900);
FORCEADD TAP..1
(-3225 5950);
FORCEPROP 3 LASTPIN (-3275 5950) SIG_NAME M_I_CPU1_SA_DQ<0>
J 0
(-3265 5960);
DISPLAY 0.659574 (-3265 5960);
PAINT MONO (-3265 5960);
DISPLAY INVISIBLE (-3265 5960);
FORCEPROP 1 LASTPIN (-3275 5950) BN 0
J 0
(-3287 5958);
DISPLAY 0.489362 (-3287 5958);
PAINT GREEN (-3287 5958);
FORCEPROP 2 LAST CDS_LIB mstr_standard
J 0
(-3225 5950);
DISPLAY 0.723404 (-3225 5950);
PAINT MONO (-3225 5950);
DISPLAY INVISIBLE (-3225 5950);
FORCEPROP 1 LAST BODY_TYPE PLUMBING
J 0
(-3225 6000);
DISPLAY 0.872340 (-3225 6000);
PAINT GREEN (-3225 6000);
DISPLAY INVISIBLE (-3225 6000);
FORCEPROP 1 LAST HDL_TAP TRUE
J 0
(-2900 5825);
DISPLAY 0.872340 (-2900 5825);
DISPLAY INVISIBLE (-2900 5825);
FORCEPROP 1 LAST PATH I163
J 0
(-3227 5950);
DISPLAY 0.872340 (-3227 5950);
PAINT GREEN (-3227 5950);
DISPLAY INVISIBLE (-3227 5950);
FORCEADD TAP..1
(-3225 5800);
FORCEPROP 3 LASTPIN (-3275 5800) SIG_NAME M_I_CPU1_SA_DQ<3>
J 0
(-3265 5810);
DISPLAY 0.659574 (-3265 5810);
PAINT MONO (-3265 5810);
DISPLAY INVISIBLE (-3265 5810);
FORCEPROP 1 LASTPIN (-3275 5800) BN 3
J 0
(-3287 5808);
DISPLAY 0.489362 (-3287 5808);
PAINT GREEN (-3287 5808);
FORCEPROP 2 LAST CDS_LIB mstr_standard
J 0
(-3225 5800);
DISPLAY 0.723404 (-3225 5800);
PAINT MONO (-3225 5800);
DISPLAY INVISIBLE (-3225 5800);
FORCEPROP 1 LAST BODY_TYPE PLUMBING
J 0
(-3225 5850);
DISPLAY 0.872340 (-3225 5850);
PAINT GREEN (-3225 5850);
DISPLAY INVISIBLE (-3225 5850);
FORCEPROP 1 LAST HDL_TAP TRUE
J 0
(-2900 5675);
DISPLAY 0.872340 (-2900 5675);
DISPLAY INVISIBLE (-2900 5675);
FORCEPROP 1 LAST PATH I164
J 0
(-3227 5800);
DISPLAY 0.872340 (-3227 5800);
PAINT GREEN (-3227 5800);
DISPLAY INVISIBLE (-3227 5800);
FORCEADD TAP..1
(-3225 5850);
FORCEPROP 3 LASTPIN (-3275 5850) SIG_NAME M_I_CPU1_SA_DQ<2>
J 0
(-3265 5860);
DISPLAY 0.659574 (-3265 5860);
PAINT MONO (-3265 5860);
DISPLAY INVISIBLE (-3265 5860);
FORCEPROP 1 LASTPIN (-3275 5850) BN 2
J 0
(-3287 5858);
DISPLAY 0.489362 (-3287 5858);
PAINT GREEN (-3287 5858);
FORCEPROP 2 LAST CDS_LIB mstr_standard
J 0
(-3225 5850);
DISPLAY 0.723404 (-3225 5850);
PAINT MONO (-3225 5850);
DISPLAY INVISIBLE (-3225 5850);
FORCEPROP 1 LAST BODY_TYPE PLUMBING
J 0
(-3225 5900);
DISPLAY 0.872340 (-3225 5900);
PAINT GREEN (-3225 5900);
DISPLAY INVISIBLE (-3225 5900);
FORCEPROP 1 LAST HDL_TAP TRUE
J 0
(-2900 5725);
DISPLAY 0.872340 (-2900 5725);
DISPLAY INVISIBLE (-2900 5725);
FORCEPROP 1 LAST PATH I165
J 0
(-3227 5850);
DISPLAY 0.872340 (-3227 5850);
PAINT GREEN (-3227 5850);
DISPLAY INVISIBLE (-3227 5850);
FORCEADD TAP..1
(-3225 5750);
FORCEPROP 3 LASTPIN (-3275 5750) SIG_NAME M_I_CPU1_SA_DQ<4>
J 0
(-3265 5760);
DISPLAY 0.659574 (-3265 5760);
PAINT MONO (-3265 5760);
DISPLAY INVISIBLE (-3265 5760);
FORCEPROP 1 LASTPIN (-3275 5750) BN 4
J 0
(-3287 5758);
DISPLAY 0.489362 (-3287 5758);
PAINT GREEN (-3287 5758);
FORCEPROP 2 LAST CDS_LIB mstr_standard
J 0
(-3225 5750);
DISPLAY 0.723404 (-3225 5750);
PAINT MONO (-3225 5750);
DISPLAY INVISIBLE (-3225 5750);
FORCEPROP 1 LAST BODY_TYPE PLUMBING
J 0
(-3225 5800);
DISPLAY 0.872340 (-3225 5800);
PAINT GREEN (-3225 5800);
DISPLAY INVISIBLE (-3225 5800);
FORCEPROP 1 LAST HDL_TAP TRUE
J 0
(-2900 5625);
DISPLAY 0.872340 (-2900 5625);
DISPLAY INVISIBLE (-2900 5625);
FORCEPROP 1 LAST PATH I166
J 0
(-3227 5750);
DISPLAY 0.872340 (-3227 5750);
PAINT GREEN (-3227 5750);
DISPLAY INVISIBLE (-3227 5750);
FORCEADD TAP..1
(-3225 5650);
FORCEPROP 3 LASTPIN (-3275 5650) SIG_NAME M_I_CPU1_SA_DQ<6>
J 0
(-3265 5660);
DISPLAY 0.659574 (-3265 5660);
PAINT MONO (-3265 5660);
DISPLAY INVISIBLE (-3265 5660);
FORCEPROP 1 LASTPIN (-3275 5650) BN 6
J 0
(-3287 5658);
DISPLAY 0.489362 (-3287 5658);
PAINT GREEN (-3287 5658);
FORCEPROP 2 LAST CDS_LIB mstr_standard
J 0
(-3225 5650);
DISPLAY 0.723404 (-3225 5650);
PAINT MONO (-3225 5650);
DISPLAY INVISIBLE (-3225 5650);
FORCEPROP 1 LAST BODY_TYPE PLUMBING
J 0
(-3225 5700);
DISPLAY 0.872340 (-3225 5700);
PAINT GREEN (-3225 5700);
DISPLAY INVISIBLE (-3225 5700);
FORCEPROP 1 LAST HDL_TAP TRUE
J 0
(-2900 5525);
DISPLAY 0.872340 (-2900 5525);
DISPLAY INVISIBLE (-2900 5525);
FORCEPROP 1 LAST PATH I167
J 0
(-3227 5650);
DISPLAY 0.872340 (-3227 5650);
PAINT GREEN (-3227 5650);
DISPLAY INVISIBLE (-3227 5650);
FORCEADD TAP..1
(-3225 5700);
FORCEPROP 3 LASTPIN (-3275 5700) SIG_NAME M_I_CPU1_SA_DQ<5>
J 0
(-3265 5710);
DISPLAY 0.659574 (-3265 5710);
PAINT MONO (-3265 5710);
DISPLAY INVISIBLE (-3265 5710);
FORCEPROP 1 LASTPIN (-3275 5700) BN 5
J 0
(-3287 5708);
DISPLAY 0.489362 (-3287 5708);
PAINT GREEN (-3287 5708);
FORCEPROP 2 LAST CDS_LIB mstr_standard
J 0
(-3225 5700);
DISPLAY 0.723404 (-3225 5700);
PAINT MONO (-3225 5700);
DISPLAY INVISIBLE (-3225 5700);
FORCEPROP 1 LAST BODY_TYPE PLUMBING
J 0
(-3225 5750);
DISPLAY 0.872340 (-3225 5750);
PAINT GREEN (-3225 5750);
DISPLAY INVISIBLE (-3225 5750);
FORCEPROP 1 LAST HDL_TAP TRUE
J 0
(-2900 5575);
DISPLAY 0.872340 (-2900 5575);
DISPLAY INVISIBLE (-2900 5575);
FORCEPROP 1 LAST PATH I168
J 0
(-3227 5700);
DISPLAY 0.872340 (-3227 5700);
PAINT GREEN (-3227 5700);
DISPLAY INVISIBLE (-3227 5700);
FORCEADD TAP..1
(-3225 5500);
FORCEPROP 3 LASTPIN (-3275 5500) SIG_NAME M_I_CPU1_SA_DQ<8>
J 0
(-3265 5510);
DISPLAY 0.659574 (-3265 5510);
PAINT MONO (-3265 5510);
DISPLAY INVISIBLE (-3265 5510);
FORCEPROP 1 LASTPIN (-3275 5500) BN 8
J 0
(-3287 5508);
DISPLAY 0.489362 (-3287 5508);
PAINT GREEN (-3287 5508);
FORCEPROP 2 LAST CDS_LIB mstr_standard
J 0
(-3225 5500);
DISPLAY 0.723404 (-3225 5500);
PAINT MONO (-3225 5500);
DISPLAY INVISIBLE (-3225 5500);
FORCEPROP 1 LAST BODY_TYPE PLUMBING
J 0
(-3225 5550);
DISPLAY 0.872340 (-3225 5550);
PAINT GREEN (-3225 5550);
DISPLAY INVISIBLE (-3225 5550);
FORCEPROP 1 LAST HDL_TAP TRUE
J 0
(-2900 5375);
DISPLAY 0.872340 (-2900 5375);
DISPLAY INVISIBLE (-2900 5375);
FORCEPROP 1 LAST PATH I169
J 0
(-3227 5500);
DISPLAY 0.872340 (-3227 5500);
PAINT GREEN (-3227 5500);
DISPLAY INVISIBLE (-3227 5500);
FORCEADD TAP..1
(-3225 5600);
FORCEPROP 3 LASTPIN (-3275 5600) SIG_NAME M_I_CPU1_SA_DQ<7>
J 0
(-3265 5610);
DISPLAY 0.659574 (-3265 5610);
PAINT MONO (-3265 5610);
DISPLAY INVISIBLE (-3265 5610);
FORCEPROP 1 LASTPIN (-3275 5600) BN 7
J 0
(-3287 5608);
DISPLAY 0.489362 (-3287 5608);
PAINT GREEN (-3287 5608);
FORCEPROP 2 LAST CDS_LIB mstr_standard
J 0
(-3225 5600);
DISPLAY 0.723404 (-3225 5600);
PAINT MONO (-3225 5600);
DISPLAY INVISIBLE (-3225 5600);
FORCEPROP 1 LAST BODY_TYPE PLUMBING
J 0
(-3225 5650);
DISPLAY 0.872340 (-3225 5650);
PAINT GREEN (-3225 5650);
DISPLAY INVISIBLE (-3225 5650);
FORCEPROP 1 LAST HDL_TAP TRUE
J 0
(-2900 5475);
DISPLAY 0.872340 (-2900 5475);
DISPLAY INVISIBLE (-2900 5475);
FORCEPROP 1 LAST PATH I170
J 0
(-3227 5600);
DISPLAY 0.872340 (-3227 5600);
PAINT GREEN (-3227 5600);
DISPLAY INVISIBLE (-3227 5600);
FORCEADD TAP..1
(-3225 5400);
FORCEPROP 3 LASTPIN (-3275 5400) SIG_NAME M_I_CPU1_SA_DQ<10>
J 0
(-3265 5410);
DISPLAY 0.659574 (-3265 5410);
PAINT MONO (-3265 5410);
DISPLAY INVISIBLE (-3265 5410);
FORCEPROP 1 LASTPIN (-3275 5400) BN 10
J 0
(-3287 5408);
DISPLAY 0.489362 (-3287 5408);
PAINT GREEN (-3287 5408);
FORCEPROP 2 LAST CDS_LIB mstr_standard
J 0
(-3225 5400);
DISPLAY 0.723404 (-3225 5400);
PAINT MONO (-3225 5400);
DISPLAY INVISIBLE (-3225 5400);
FORCEPROP 1 LAST BODY_TYPE PLUMBING
J 0
(-3225 5450);
DISPLAY 0.872340 (-3225 5450);
PAINT GREEN (-3225 5450);
DISPLAY INVISIBLE (-3225 5450);
FORCEPROP 1 LAST HDL_TAP TRUE
J 0
(-2900 5275);
DISPLAY 0.872340 (-2900 5275);
DISPLAY INVISIBLE (-2900 5275);
FORCEPROP 1 LAST PATH I171
J 0
(-3227 5400);
DISPLAY 0.872340 (-3227 5400);
PAINT GREEN (-3227 5400);
DISPLAY INVISIBLE (-3227 5400);
FORCEADD TAP..1
(-3225 5450);
FORCEPROP 3 LASTPIN (-3275 5450) SIG_NAME M_I_CPU1_SA_DQ<9>
J 0
(-3265 5460);
DISPLAY 0.659574 (-3265 5460);
PAINT MONO (-3265 5460);
DISPLAY INVISIBLE (-3265 5460);
FORCEPROP 1 LASTPIN (-3275 5450) BN 9
J 0
(-3287 5458);
DISPLAY 0.489362 (-3287 5458);
PAINT GREEN (-3287 5458);
FORCEPROP 2 LAST CDS_LIB mstr_standard
J 0
(-3225 5450);
DISPLAY 0.723404 (-3225 5450);
PAINT MONO (-3225 5450);
DISPLAY INVISIBLE (-3225 5450);
FORCEPROP 1 LAST BODY_TYPE PLUMBING
J 0
(-3225 5500);
DISPLAY 0.872340 (-3225 5500);
PAINT GREEN (-3225 5500);
DISPLAY INVISIBLE (-3225 5500);
FORCEPROP 1 LAST HDL_TAP TRUE
J 0
(-2900 5325);
DISPLAY 0.872340 (-2900 5325);
DISPLAY INVISIBLE (-2900 5325);
FORCEPROP 1 LAST PATH I172
J 0
(-3227 5450);
DISPLAY 0.872340 (-3227 5450);
PAINT GREEN (-3227 5450);
DISPLAY INVISIBLE (-3227 5450);
FORCEADD TAP..1
(-3225 5250);
FORCEPROP 3 LASTPIN (-3275 5250) SIG_NAME M_I_CPU1_SA_DQ<13>
J 0
(-3265 5260);
DISPLAY 0.659574 (-3265 5260);
PAINT MONO (-3265 5260);
DISPLAY INVISIBLE (-3265 5260);
FORCEPROP 1 LASTPIN (-3275 5250) BN 13
J 0
(-3287 5258);
DISPLAY 0.489362 (-3287 5258);
PAINT GREEN (-3287 5258);
FORCEPROP 2 LAST CDS_LIB mstr_standard
J 0
(-3225 5250);
DISPLAY 0.723404 (-3225 5250);
PAINT MONO (-3225 5250);
DISPLAY INVISIBLE (-3225 5250);
FORCEPROP 1 LAST BODY_TYPE PLUMBING
J 0
(-3225 5300);
DISPLAY 0.872340 (-3225 5300);
PAINT GREEN (-3225 5300);
DISPLAY INVISIBLE (-3225 5300);
FORCEPROP 1 LAST HDL_TAP TRUE
J 0
(-2900 5125);
DISPLAY 0.872340 (-2900 5125);
DISPLAY INVISIBLE (-2900 5125);
FORCEPROP 1 LAST PATH I173
J 0
(-3227 5250);
DISPLAY 0.872340 (-3227 5250);
PAINT GREEN (-3227 5250);
DISPLAY INVISIBLE (-3227 5250);
FORCEADD TAP..1
(-3225 5300);
FORCEPROP 3 LASTPIN (-3275 5300) SIG_NAME M_I_CPU1_SA_DQ<12>
J 0
(-3265 5310);
DISPLAY 0.659574 (-3265 5310);
PAINT MONO (-3265 5310);
DISPLAY INVISIBLE (-3265 5310);
FORCEPROP 1 LASTPIN (-3275 5300) BN 12
J 0
(-3287 5308);
DISPLAY 0.489362 (-3287 5308);
PAINT GREEN (-3287 5308);
FORCEPROP 2 LAST CDS_LIB mstr_standard
J 0
(-3225 5300);
DISPLAY 0.723404 (-3225 5300);
PAINT MONO (-3225 5300);
DISPLAY INVISIBLE (-3225 5300);
FORCEPROP 1 LAST BODY_TYPE PLUMBING
J 0
(-3225 5350);
DISPLAY 0.872340 (-3225 5350);
PAINT GREEN (-3225 5350);
DISPLAY INVISIBLE (-3225 5350);
FORCEPROP 1 LAST HDL_TAP TRUE
J 0
(-2900 5175);
DISPLAY 0.872340 (-2900 5175);
DISPLAY INVISIBLE (-2900 5175);
FORCEPROP 1 LAST PATH I174
J 0
(-3227 5300);
DISPLAY 0.872340 (-3227 5300);
PAINT GREEN (-3227 5300);
DISPLAY INVISIBLE (-3227 5300);
FORCEADD TAP..1
(-3225 5350);
FORCEPROP 3 LASTPIN (-3275 5350) SIG_NAME M_I_CPU1_SA_DQ<11>
J 0
(-3265 5360);
DISPLAY 0.659574 (-3265 5360);
PAINT MONO (-3265 5360);
DISPLAY INVISIBLE (-3265 5360);
FORCEPROP 1 LASTPIN (-3275 5350) BN 11
J 0
(-3287 5358);
DISPLAY 0.489362 (-3287 5358);
PAINT GREEN (-3287 5358);
FORCEPROP 2 LAST CDS_LIB mstr_standard
J 0
(-3225 5350);
DISPLAY 0.723404 (-3225 5350);
PAINT MONO (-3225 5350);
DISPLAY INVISIBLE (-3225 5350);
FORCEPROP 1 LAST BODY_TYPE PLUMBING
J 0
(-3225 5400);
DISPLAY 0.872340 (-3225 5400);
PAINT GREEN (-3225 5400);
DISPLAY INVISIBLE (-3225 5400);
FORCEPROP 1 LAST HDL_TAP TRUE
J 0
(-2900 5225);
DISPLAY 0.872340 (-2900 5225);
DISPLAY INVISIBLE (-2900 5225);
FORCEPROP 1 LAST PATH I175
J 0
(-3227 5350);
DISPLAY 0.872340 (-3227 5350);
PAINT GREEN (-3227 5350);
DISPLAY INVISIBLE (-3227 5350);
FORCEADD TAP..1
(-3225 5200);
FORCEPROP 3 LASTPIN (-3275 5200) SIG_NAME M_I_CPU1_SA_DQ<14>
J 0
(-3265 5210);
DISPLAY 0.659574 (-3265 5210);
PAINT MONO (-3265 5210);
DISPLAY INVISIBLE (-3265 5210);
FORCEPROP 1 LASTPIN (-3275 5200) BN 14
J 0
(-3287 5208);
DISPLAY 0.489362 (-3287 5208);
PAINT GREEN (-3287 5208);
FORCEPROP 2 LAST CDS_LIB mstr_standard
J 0
(-3225 5200);
DISPLAY 0.723404 (-3225 5200);
PAINT MONO (-3225 5200);
DISPLAY INVISIBLE (-3225 5200);
FORCEPROP 1 LAST BODY_TYPE PLUMBING
J 0
(-3225 5250);
DISPLAY 0.872340 (-3225 5250);
PAINT GREEN (-3225 5250);
DISPLAY INVISIBLE (-3225 5250);
FORCEPROP 1 LAST HDL_TAP TRUE
J 0
(-2900 5075);
DISPLAY 0.872340 (-2900 5075);
DISPLAY INVISIBLE (-2900 5075);
FORCEPROP 1 LAST PATH I176
J 0
(-3227 5200);
DISPLAY 0.872340 (-3227 5200);
PAINT GREEN (-3227 5200);
DISPLAY INVISIBLE (-3227 5200);
FORCEADD TAP..1
(-3225 5150);
FORCEPROP 3 LASTPIN (-3275 5150) SIG_NAME M_I_CPU1_SA_DQ<15>
J 0
(-3265 5160);
DISPLAY 0.659574 (-3265 5160);
PAINT MONO (-3265 5160);
DISPLAY INVISIBLE (-3265 5160);
FORCEPROP 1 LASTPIN (-3275 5150) BN 15
J 0
(-3287 5158);
DISPLAY 0.489362 (-3287 5158);
PAINT GREEN (-3287 5158);
FORCEPROP 2 LAST CDS_LIB mstr_standard
J 0
(-3225 5150);
DISPLAY 0.723404 (-3225 5150);
PAINT MONO (-3225 5150);
DISPLAY INVISIBLE (-3225 5150);
FORCEPROP 1 LAST BODY_TYPE PLUMBING
J 0
(-3225 5200);
DISPLAY 0.872340 (-3225 5200);
PAINT GREEN (-3225 5200);
DISPLAY INVISIBLE (-3225 5200);
FORCEPROP 1 LAST HDL_TAP TRUE
J 0
(-2900 5025);
DISPLAY 0.872340 (-2900 5025);
DISPLAY INVISIBLE (-2900 5025);
FORCEPROP 1 LAST PATH I177
J 0
(-3227 5150);
DISPLAY 0.872340 (-3227 5150);
PAINT GREEN (-3227 5150);
DISPLAY INVISIBLE (-3227 5150);
FORCEADD TAP..1
(-3225 5050);
FORCEPROP 3 LASTPIN (-3275 5050) SIG_NAME M_I_CPU1_SA_DQ<16>
J 0
(-3265 5060);
DISPLAY 0.659574 (-3265 5060);
PAINT MONO (-3265 5060);
DISPLAY INVISIBLE (-3265 5060);
FORCEPROP 1 LASTPIN (-3275 5050) BN 16
J 0
(-3287 5058);
DISPLAY 0.489362 (-3287 5058);
PAINT GREEN (-3287 5058);
FORCEPROP 2 LAST CDS_LIB mstr_standard
J 0
(-3225 5050);
DISPLAY 0.723404 (-3225 5050);
PAINT MONO (-3225 5050);
DISPLAY INVISIBLE (-3225 5050);
FORCEPROP 1 LAST BODY_TYPE PLUMBING
J 0
(-3225 5100);
DISPLAY 0.872340 (-3225 5100);
PAINT GREEN (-3225 5100);
DISPLAY INVISIBLE (-3225 5100);
FORCEPROP 1 LAST HDL_TAP TRUE
J 0
(-2900 4925);
DISPLAY 0.872340 (-2900 4925);
DISPLAY INVISIBLE (-2900 4925);
FORCEPROP 1 LAST PATH I178
J 0
(-3227 5050);
DISPLAY 0.872340 (-3227 5050);
PAINT GREEN (-3227 5050);
DISPLAY INVISIBLE (-3227 5050);
FORCEADD TAP..1
(-3225 5000);
FORCEPROP 3 LASTPIN (-3275 5000) SIG_NAME M_I_CPU1_SA_DQ<17>
J 0
(-3265 5010);
DISPLAY 0.659574 (-3265 5010);
PAINT MONO (-3265 5010);
DISPLAY INVISIBLE (-3265 5010);
FORCEPROP 1 LASTPIN (-3275 5000) BN 17
J 0
(-3287 5008);
DISPLAY 0.489362 (-3287 5008);
PAINT GREEN (-3287 5008);
FORCEPROP 2 LAST CDS_LIB mstr_standard
J 0
(-3225 5000);
DISPLAY 0.723404 (-3225 5000);
PAINT MONO (-3225 5000);
DISPLAY INVISIBLE (-3225 5000);
FORCEPROP 1 LAST BODY_TYPE PLUMBING
J 0
(-3225 5050);
DISPLAY 0.872340 (-3225 5050);
PAINT GREEN (-3225 5050);
DISPLAY INVISIBLE (-3225 5050);
FORCEPROP 1 LAST HDL_TAP TRUE
J 0
(-2900 4875);
DISPLAY 0.872340 (-2900 4875);
DISPLAY INVISIBLE (-2900 4875);
FORCEPROP 1 LAST PATH I179
J 0
(-3227 5000);
DISPLAY 0.872340 (-3227 5000);
PAINT GREEN (-3227 5000);
DISPLAY INVISIBLE (-3227 5000);
FORCEADD TAP..1
(-3225 4900);
FORCEPROP 3 LASTPIN (-3275 4900) SIG_NAME M_I_CPU1_SA_DQ<19>
J 0
(-3265 4910);
DISPLAY 0.659574 (-3265 4910);
PAINT MONO (-3265 4910);
DISPLAY INVISIBLE (-3265 4910);
FORCEPROP 1 LASTPIN (-3275 4900) BN 19
J 0
(-3287 4908);
DISPLAY 0.489362 (-3287 4908);
PAINT GREEN (-3287 4908);
FORCEPROP 2 LAST CDS_LIB mstr_standard
J 0
(-3225 4900);
DISPLAY 0.723404 (-3225 4900);
PAINT MONO (-3225 4900);
DISPLAY INVISIBLE (-3225 4900);
FORCEPROP 1 LAST BODY_TYPE PLUMBING
J 0
(-3225 4950);
DISPLAY 0.872340 (-3225 4950);
PAINT GREEN (-3225 4950);
DISPLAY INVISIBLE (-3225 4950);
FORCEPROP 1 LAST HDL_TAP TRUE
J 0
(-2900 4775);
DISPLAY 0.872340 (-2900 4775);
DISPLAY INVISIBLE (-2900 4775);
FORCEPROP 1 LAST PATH I180
J 0
(-3227 4900);
DISPLAY 0.872340 (-3227 4900);
PAINT GREEN (-3227 4900);
DISPLAY INVISIBLE (-3227 4900);
FORCEADD TAP..1
(-3225 4950);
FORCEPROP 3 LASTPIN (-3275 4950) SIG_NAME M_I_CPU1_SA_DQ<18>
J 0
(-3265 4960);
DISPLAY 0.659574 (-3265 4960);
PAINT MONO (-3265 4960);
DISPLAY INVISIBLE (-3265 4960);
FORCEPROP 1 LASTPIN (-3275 4950) BN 18
J 0
(-3287 4958);
DISPLAY 0.489362 (-3287 4958);
PAINT GREEN (-3287 4958);
FORCEPROP 2 LAST CDS_LIB mstr_standard
J 0
(-3225 4950);
DISPLAY 0.723404 (-3225 4950);
PAINT MONO (-3225 4950);
DISPLAY INVISIBLE (-3225 4950);
FORCEPROP 1 LAST BODY_TYPE PLUMBING
J 0
(-3225 5000);
DISPLAY 0.872340 (-3225 5000);
PAINT GREEN (-3225 5000);
DISPLAY INVISIBLE (-3225 5000);
FORCEPROP 1 LAST HDL_TAP TRUE
J 0
(-2900 4825);
DISPLAY 0.872340 (-2900 4825);
DISPLAY INVISIBLE (-2900 4825);
FORCEPROP 1 LAST PATH I181
J 0
(-3227 4950);
DISPLAY 0.872340 (-3227 4950);
PAINT GREEN (-3227 4950);
DISPLAY INVISIBLE (-3227 4950);
FORCEADD TAP..1
(-3225 4850);
FORCEPROP 3 LASTPIN (-3275 4850) SIG_NAME M_I_CPU1_SA_DQ<20>
J 0
(-3265 4860);
DISPLAY 0.659574 (-3265 4860);
PAINT MONO (-3265 4860);
DISPLAY INVISIBLE (-3265 4860);
FORCEPROP 1 LASTPIN (-3275 4850) BN 20
J 0
(-3287 4858);
DISPLAY 0.489362 (-3287 4858);
PAINT GREEN (-3287 4858);
FORCEPROP 2 LAST CDS_LIB mstr_standard
J 0
(-3225 4850);
DISPLAY 0.723404 (-3225 4850);
PAINT MONO (-3225 4850);
DISPLAY INVISIBLE (-3225 4850);
FORCEPROP 1 LAST BODY_TYPE PLUMBING
J 0
(-3225 4900);
DISPLAY 0.872340 (-3225 4900);
PAINT GREEN (-3225 4900);
DISPLAY INVISIBLE (-3225 4900);
FORCEPROP 1 LAST HDL_TAP TRUE
J 0
(-2900 4725);
DISPLAY 0.872340 (-2900 4725);
DISPLAY INVISIBLE (-2900 4725);
FORCEPROP 1 LAST PATH I182
J 0
(-3227 4850);
DISPLAY 0.872340 (-3227 4850);
PAINT GREEN (-3227 4850);
DISPLAY INVISIBLE (-3227 4850);
FORCEADD TAP..1
(-3225 4750);
FORCEPROP 3 LASTPIN (-3275 4750) SIG_NAME M_I_CPU1_SA_DQ<22>
J 0
(-3265 4760);
DISPLAY 0.659574 (-3265 4760);
PAINT MONO (-3265 4760);
DISPLAY INVISIBLE (-3265 4760);
FORCEPROP 1 LASTPIN (-3275 4750) BN 22
J 0
(-3287 4758);
DISPLAY 0.489362 (-3287 4758);
PAINT GREEN (-3287 4758);
FORCEPROP 2 LAST CDS_LIB mstr_standard
J 0
(-3225 4750);
DISPLAY 0.723404 (-3225 4750);
PAINT MONO (-3225 4750);
DISPLAY INVISIBLE (-3225 4750);
FORCEPROP 1 LAST BODY_TYPE PLUMBING
J 0
(-3225 4800);
DISPLAY 0.872340 (-3225 4800);
PAINT GREEN (-3225 4800);
DISPLAY INVISIBLE (-3225 4800);
FORCEPROP 1 LAST HDL_TAP TRUE
J 0
(-2900 4625);
DISPLAY 0.872340 (-2900 4625);
DISPLAY INVISIBLE (-2900 4625);
FORCEPROP 1 LAST PATH I183
J 0
(-3227 4750);
DISPLAY 0.872340 (-3227 4750);
PAINT GREEN (-3227 4750);
DISPLAY INVISIBLE (-3227 4750);
FORCEADD TAP..1
(-3225 4800);
FORCEPROP 3 LASTPIN (-3275 4800) SIG_NAME M_I_CPU1_SA_DQ<21>
J 0
(-3265 4810);
DISPLAY 0.659574 (-3265 4810);
PAINT MONO (-3265 4810);
DISPLAY INVISIBLE (-3265 4810);
FORCEPROP 1 LASTPIN (-3275 4800) BN 21
J 0
(-3287 4808);
DISPLAY 0.489362 (-3287 4808);
PAINT GREEN (-3287 4808);
FORCEPROP 2 LAST CDS_LIB mstr_standard
J 0
(-3225 4800);
DISPLAY 0.723404 (-3225 4800);
PAINT MONO (-3225 4800);
DISPLAY INVISIBLE (-3225 4800);
FORCEPROP 1 LAST BODY_TYPE PLUMBING
J 0
(-3225 4850);
DISPLAY 0.872340 (-3225 4850);
PAINT GREEN (-3225 4850);
DISPLAY INVISIBLE (-3225 4850);
FORCEPROP 1 LAST HDL_TAP TRUE
J 0
(-2900 4675);
DISPLAY 0.872340 (-2900 4675);
DISPLAY INVISIBLE (-2900 4675);
FORCEPROP 1 LAST PATH I184
J 0
(-3227 4800);
DISPLAY 0.872340 (-3227 4800);
PAINT GREEN (-3227 4800);
DISPLAY INVISIBLE (-3227 4800);
FORCEADD TAP..1
(-3225 4700);
FORCEPROP 3 LASTPIN (-3275 4700) SIG_NAME M_I_CPU1_SA_DQ<23>
J 0
(-3265 4710);
DISPLAY 0.659574 (-3265 4710);
PAINT MONO (-3265 4710);
DISPLAY INVISIBLE (-3265 4710);
FORCEPROP 1 LASTPIN (-3275 4700) BN 23
J 0
(-3287 4708);
DISPLAY 0.489362 (-3287 4708);
PAINT GREEN (-3287 4708);
FORCEPROP 2 LAST CDS_LIB mstr_standard
J 0
(-3225 4700);
DISPLAY 0.723404 (-3225 4700);
PAINT MONO (-3225 4700);
DISPLAY INVISIBLE (-3225 4700);
FORCEPROP 1 LAST BODY_TYPE PLUMBING
J 0
(-3225 4750);
DISPLAY 0.872340 (-3225 4750);
PAINT GREEN (-3225 4750);
DISPLAY INVISIBLE (-3225 4750);
FORCEPROP 1 LAST HDL_TAP TRUE
J 0
(-2900 4575);
DISPLAY 0.872340 (-2900 4575);
DISPLAY INVISIBLE (-2900 4575);
FORCEPROP 1 LAST PATH I185
J 0
(-3227 4700);
DISPLAY 0.872340 (-3227 4700);
PAINT GREEN (-3227 4700);
DISPLAY INVISIBLE (-3227 4700);
FORCEADD TAP..1
(-3225 4500);
FORCEPROP 3 LASTPIN (-3275 4500) SIG_NAME M_I_CPU1_SA_DQ<26>
J 0
(-3265 4510);
DISPLAY 0.659574 (-3265 4510);
PAINT MONO (-3265 4510);
DISPLAY INVISIBLE (-3265 4510);
FORCEPROP 1 LASTPIN (-3275 4500) BN 26
J 0
(-3287 4508);
DISPLAY 0.489362 (-3287 4508);
PAINT GREEN (-3287 4508);
FORCEPROP 2 LAST CDS_LIB mstr_standard
J 0
(-3225 4500);
DISPLAY 0.723404 (-3225 4500);
PAINT MONO (-3225 4500);
DISPLAY INVISIBLE (-3225 4500);
FORCEPROP 1 LAST BODY_TYPE PLUMBING
J 0
(-3225 4550);
DISPLAY 0.872340 (-3225 4550);
PAINT GREEN (-3225 4550);
DISPLAY INVISIBLE (-3225 4550);
FORCEPROP 1 LAST HDL_TAP TRUE
J 0
(-2900 4375);
DISPLAY 0.872340 (-2900 4375);
DISPLAY INVISIBLE (-2900 4375);
FORCEPROP 1 LAST PATH I186
J 0
(-3227 4500);
DISPLAY 0.872340 (-3227 4500);
PAINT GREEN (-3227 4500);
DISPLAY INVISIBLE (-3227 4500);
FORCEADD TAP..1
(-3225 4600);
FORCEPROP 3 LASTPIN (-3275 4600) SIG_NAME M_I_CPU1_SA_DQ<24>
J 0
(-3265 4610);
DISPLAY 0.659574 (-3265 4610);
PAINT MONO (-3265 4610);
DISPLAY INVISIBLE (-3265 4610);
FORCEPROP 1 LASTPIN (-3275 4600) BN 24
J 0
(-3287 4608);
DISPLAY 0.489362 (-3287 4608);
PAINT GREEN (-3287 4608);
FORCEPROP 2 LAST CDS_LIB mstr_standard
J 0
(-3225 4600);
DISPLAY 0.723404 (-3225 4600);
PAINT MONO (-3225 4600);
DISPLAY INVISIBLE (-3225 4600);
FORCEPROP 1 LAST BODY_TYPE PLUMBING
J 0
(-3225 4650);
DISPLAY 0.872340 (-3225 4650);
PAINT GREEN (-3225 4650);
DISPLAY INVISIBLE (-3225 4650);
FORCEPROP 1 LAST HDL_TAP TRUE
J 0
(-2900 4475);
DISPLAY 0.872340 (-2900 4475);
DISPLAY INVISIBLE (-2900 4475);
FORCEPROP 1 LAST PATH I187
J 0
(-3227 4600);
DISPLAY 0.872340 (-3227 4600);
PAINT GREEN (-3227 4600);
DISPLAY INVISIBLE (-3227 4600);
FORCEADD TAP..1
(-3225 4550);
FORCEPROP 3 LASTPIN (-3275 4550) SIG_NAME M_I_CPU1_SA_DQ<25>
J 0
(-3265 4560);
DISPLAY 0.659574 (-3265 4560);
PAINT MONO (-3265 4560);
DISPLAY INVISIBLE (-3265 4560);
FORCEPROP 1 LASTPIN (-3275 4550) BN 25
J 0
(-3287 4558);
DISPLAY 0.489362 (-3287 4558);
PAINT GREEN (-3287 4558);
FORCEPROP 2 LAST CDS_LIB mstr_standard
J 0
(-3225 4550);
DISPLAY 0.723404 (-3225 4550);
PAINT MONO (-3225 4550);
DISPLAY INVISIBLE (-3225 4550);
FORCEPROP 1 LAST BODY_TYPE PLUMBING
J 0
(-3225 4600);
DISPLAY 0.872340 (-3225 4600);
PAINT GREEN (-3225 4600);
DISPLAY INVISIBLE (-3225 4600);
FORCEPROP 1 LAST HDL_TAP TRUE
J 0
(-2900 4425);
DISPLAY 0.872340 (-2900 4425);
DISPLAY INVISIBLE (-2900 4425);
FORCEPROP 1 LAST PATH I188
J 0
(-3227 4550);
DISPLAY 0.872340 (-3227 4550);
PAINT GREEN (-3227 4550);
DISPLAY INVISIBLE (-3227 4550);
FORCEADD TAP..1
(-3225 4400);
FORCEPROP 3 LASTPIN (-3275 4400) SIG_NAME M_I_CPU1_SA_DQ<28>
J 0
(-3265 4410);
DISPLAY 0.659574 (-3265 4410);
PAINT MONO (-3265 4410);
DISPLAY INVISIBLE (-3265 4410);
FORCEPROP 1 LASTPIN (-3275 4400) BN 28
J 0
(-3287 4408);
DISPLAY 0.489362 (-3287 4408);
PAINT GREEN (-3287 4408);
FORCEPROP 2 LAST CDS_LIB mstr_standard
J 0
(-3225 4400);
DISPLAY 0.723404 (-3225 4400);
PAINT MONO (-3225 4400);
DISPLAY INVISIBLE (-3225 4400);
FORCEPROP 1 LAST BODY_TYPE PLUMBING
J 0
(-3225 4450);
DISPLAY 0.872340 (-3225 4450);
PAINT GREEN (-3225 4450);
DISPLAY INVISIBLE (-3225 4450);
FORCEPROP 1 LAST HDL_TAP TRUE
J 0
(-2900 4275);
DISPLAY 0.872340 (-2900 4275);
DISPLAY INVISIBLE (-2900 4275);
FORCEPROP 1 LAST PATH I189
J 0
(-3227 4400);
DISPLAY 0.872340 (-3227 4400);
PAINT GREEN (-3227 4400);
DISPLAY INVISIBLE (-3227 4400);
FORCEADD TAP..1
(-3225 4450);
FORCEPROP 3 LASTPIN (-3275 4450) SIG_NAME M_I_CPU1_SA_DQ<27>
J 0
(-3265 4460);
DISPLAY 0.659574 (-3265 4460);
PAINT MONO (-3265 4460);
DISPLAY INVISIBLE (-3265 4460);
FORCEPROP 1 LASTPIN (-3275 4450) BN 27
J 0
(-3287 4458);
DISPLAY 0.489362 (-3287 4458);
PAINT GREEN (-3287 4458);
FORCEPROP 2 LAST CDS_LIB mstr_standard
J 0
(-3225 4450);
DISPLAY 0.723404 (-3225 4450);
PAINT MONO (-3225 4450);
DISPLAY INVISIBLE (-3225 4450);
FORCEPROP 1 LAST BODY_TYPE PLUMBING
J 0
(-3225 4500);
DISPLAY 0.872340 (-3225 4500);
PAINT GREEN (-3225 4500);
DISPLAY INVISIBLE (-3225 4500);
FORCEPROP 1 LAST HDL_TAP TRUE
J 0
(-2900 4325);
DISPLAY 0.872340 (-2900 4325);
DISPLAY INVISIBLE (-2900 4325);
FORCEPROP 1 LAST PATH I190
J 0
(-3227 4450);
DISPLAY 0.872340 (-3227 4450);
PAINT GREEN (-3227 4450);
DISPLAY INVISIBLE (-3227 4450);
FORCEADD TAP..1
(-3225 4350);
FORCEPROP 3 LASTPIN (-3275 4350) SIG_NAME M_I_CPU1_SA_DQ<29>
J 0
(-3265 4360);
DISPLAY 0.659574 (-3265 4360);
PAINT MONO (-3265 4360);
DISPLAY INVISIBLE (-3265 4360);
FORCEPROP 1 LASTPIN (-3275 4350) BN 29
J 0
(-3287 4358);
DISPLAY 0.489362 (-3287 4358);
PAINT GREEN (-3287 4358);
FORCEPROP 2 LAST CDS_LIB mstr_standard
J 0
(-3225 4350);
DISPLAY 0.723404 (-3225 4350);
PAINT MONO (-3225 4350);
DISPLAY INVISIBLE (-3225 4350);
FORCEPROP 1 LAST BODY_TYPE PLUMBING
J 0
(-3225 4400);
DISPLAY 0.872340 (-3225 4400);
PAINT GREEN (-3225 4400);
DISPLAY INVISIBLE (-3225 4400);
FORCEPROP 1 LAST HDL_TAP TRUE
J 0
(-2900 4225);
DISPLAY 0.872340 (-2900 4225);
DISPLAY INVISIBLE (-2900 4225);
FORCEPROP 1 LAST PATH I191
J 0
(-3227 4350);
DISPLAY 0.872340 (-3227 4350);
PAINT GREEN (-3227 4350);
DISPLAY INVISIBLE (-3227 4350);
FORCEADD TAP..1
(-3225 4300);
FORCEPROP 3 LASTPIN (-3275 4300) SIG_NAME M_I_CPU1_SA_DQ<30>
J 0
(-3265 4310);
DISPLAY 0.659574 (-3265 4310);
PAINT MONO (-3265 4310);
DISPLAY INVISIBLE (-3265 4310);
FORCEPROP 1 LASTPIN (-3275 4300) BN 30
J 0
(-3287 4308);
DISPLAY 0.489362 (-3287 4308);
PAINT GREEN (-3287 4308);
FORCEPROP 2 LAST CDS_LIB mstr_standard
J 0
(-3225 4300);
DISPLAY 0.723404 (-3225 4300);
PAINT MONO (-3225 4300);
DISPLAY INVISIBLE (-3225 4300);
FORCEPROP 1 LAST BODY_TYPE PLUMBING
J 0
(-3225 4350);
DISPLAY 0.872340 (-3225 4350);
PAINT GREEN (-3225 4350);
DISPLAY INVISIBLE (-3225 4350);
FORCEPROP 1 LAST HDL_TAP TRUE
J 0
(-2900 4175);
DISPLAY 0.872340 (-2900 4175);
DISPLAY INVISIBLE (-2900 4175);
FORCEPROP 1 LAST PATH I192
J 0
(-3227 4300);
DISPLAY 0.872340 (-3227 4300);
PAINT GREEN (-3227 4300);
DISPLAY INVISIBLE (-3227 4300);
FORCEADD TAP..1
(-3225 4250);
FORCEPROP 3 LASTPIN (-3275 4250) SIG_NAME M_I_CPU1_SA_DQ<31>
J 0
(-3265 4260);
DISPLAY 0.659574 (-3265 4260);
PAINT MONO (-3265 4260);
DISPLAY INVISIBLE (-3265 4260);
FORCEPROP 1 LASTPIN (-3275 4250) BN 31
J 0
(-3287 4258);
DISPLAY 0.489362 (-3287 4258);
PAINT GREEN (-3287 4258);
FORCEPROP 2 LAST CDS_LIB mstr_standard
J 0
(-3225 4250);
DISPLAY 0.723404 (-3225 4250);
PAINT MONO (-3225 4250);
DISPLAY INVISIBLE (-3225 4250);
FORCEPROP 1 LAST BODY_TYPE PLUMBING
J 0
(-3225 4300);
DISPLAY 0.872340 (-3225 4300);
PAINT GREEN (-3225 4300);
DISPLAY INVISIBLE (-3225 4300);
FORCEPROP 1 LAST HDL_TAP TRUE
J 0
(-2900 4125);
DISPLAY 0.872340 (-2900 4125);
DISPLAY INVISIBLE (-2900 4125);
FORCEPROP 1 LAST PATH I193
J 0
(-3227 4250);
DISPLAY 0.872340 (-3227 4250);
PAINT GREEN (-3227 4250);
DISPLAY INVISIBLE (-3227 4250);
FORCEADD TAP..1
(-3225 4150);
FORCEPROP 3 LASTPIN (-3275 4150) SIG_NAME M_I_CPU1_SB_DQ<0>
J 0
(-3265 4160);
DISPLAY 0.659574 (-3265 4160);
PAINT MONO (-3265 4160);
DISPLAY INVISIBLE (-3265 4160);
FORCEPROP 1 LASTPIN (-3275 4150) BN 0
J 0
(-3287 4158);
DISPLAY 0.489362 (-3287 4158);
PAINT GREEN (-3287 4158);
FORCEPROP 2 LAST CDS_LIB mstr_standard
J 0
(-3225 4150);
DISPLAY 0.723404 (-3225 4150);
PAINT MONO (-3225 4150);
DISPLAY INVISIBLE (-3225 4150);
FORCEPROP 1 LAST BODY_TYPE PLUMBING
J 0
(-3225 4200);
DISPLAY 0.872340 (-3225 4200);
PAINT GREEN (-3225 4200);
DISPLAY INVISIBLE (-3225 4200);
FORCEPROP 1 LAST HDL_TAP TRUE
J 0
(-2900 4025);
DISPLAY 0.872340 (-2900 4025);
DISPLAY INVISIBLE (-2900 4025);
FORCEPROP 1 LAST PATH I194
J 0
(-3227 4150);
DISPLAY 0.872340 (-3227 4150);
PAINT GREEN (-3227 4150);
DISPLAY INVISIBLE (-3227 4150);
FORCEADD TAP..1
(-3225 4100);
FORCEPROP 3 LASTPIN (-3275 4100) SIG_NAME M_I_CPU1_SB_DQ<1>
J 0
(-3265 4110);
DISPLAY 0.659574 (-3265 4110);
PAINT MONO (-3265 4110);
DISPLAY INVISIBLE (-3265 4110);
FORCEPROP 1 LASTPIN (-3275 4100) BN 1
J 0
(-3287 4108);
DISPLAY 0.489362 (-3287 4108);
PAINT GREEN (-3287 4108);
FORCEPROP 2 LAST CDS_LIB mstr_standard
J 0
(-3225 4100);
DISPLAY 0.723404 (-3225 4100);
PAINT MONO (-3225 4100);
DISPLAY INVISIBLE (-3225 4100);
FORCEPROP 1 LAST BODY_TYPE PLUMBING
J 0
(-3225 4150);
DISPLAY 0.872340 (-3225 4150);
PAINT GREEN (-3225 4150);
DISPLAY INVISIBLE (-3225 4150);
FORCEPROP 1 LAST HDL_TAP TRUE
J 0
(-2900 3975);
DISPLAY 0.872340 (-2900 3975);
DISPLAY INVISIBLE (-2900 3975);
FORCEPROP 1 LAST PATH I195
J 0
(-3227 4100);
DISPLAY 0.872340 (-3227 4100);
PAINT GREEN (-3227 4100);
DISPLAY INVISIBLE (-3227 4100);
FORCEADD OFFPAGE..6
R 2
(-2625 2400);
FORCEPROP 2 LAST $XR0 106 
J 0
(-2411 2400);
DISPLAY 0.638298 (-2411 2400);
PAINT MONO (-2411 2400);
FORCEPROP 2 LAST CDS_LIB mstr_standard
J 2
(-2625 2400);
DISPLAY 0.723404 (-2625 2400);
PAINT MONO (-2625 2400);
DISPLAY INVISIBLE (-2625 2400);
FORCEPROP 1 LAST OFFPAGE TRUE
J 2
(-2950 2275);
DISPLAY 0.872340 (-2950 2275);
PAINT GREEN (-2950 2275);
DISPLAY INVISIBLE (-2950 2275);
FORCEPROP 1 LAST COMMENT_BODY TRUE
J 2
(-2725 2325);
DISPLAY 0.872340 (-2725 2325);
PAINT GREEN (-2725 2325);
DISPLAY INVISIBLE (-2725 2325);
FORCEPROP 2 LAST PATH I196
J 0
(-2400 2450);
DISPLAY 1.021277 (-2400 2450);
DISPLAY INVISIBLE (-2400 2450);
FORCEADD TAP..1
(-3225 4050);
FORCEPROP 3 LASTPIN (-3275 4050) SIG_NAME M_I_CPU1_SB_DQ<2>
J 0
(-3265 4060);
DISPLAY 0.659574 (-3265 4060);
PAINT MONO (-3265 4060);
DISPLAY INVISIBLE (-3265 4060);
FORCEPROP 1 LASTPIN (-3275 4050) BN 2
J 0
(-3287 4058);
DISPLAY 0.489362 (-3287 4058);
PAINT GREEN (-3287 4058);
FORCEPROP 2 LAST CDS_LIB mstr_standard
J 0
(-3225 4050);
DISPLAY 0.723404 (-3225 4050);
PAINT MONO (-3225 4050);
DISPLAY INVISIBLE (-3225 4050);
FORCEPROP 1 LAST BODY_TYPE PLUMBING
J 0
(-3225 4100);
DISPLAY 0.872340 (-3225 4100);
PAINT GREEN (-3225 4100);
DISPLAY INVISIBLE (-3225 4100);
FORCEPROP 1 LAST HDL_TAP TRUE
J 0
(-2900 3925);
DISPLAY 0.872340 (-2900 3925);
DISPLAY INVISIBLE (-2900 3925);
FORCEPROP 1 LAST PATH I197
J 0
(-3227 4050);
DISPLAY 0.872340 (-3227 4050);
PAINT GREEN (-3227 4050);
DISPLAY INVISIBLE (-3227 4050);
FORCEADD TAP..1
(-3225 4000);
FORCEPROP 3 LASTPIN (-3275 4000) SIG_NAME M_I_CPU1_SB_DQ<3>
J 0
(-3265 4010);
DISPLAY 0.659574 (-3265 4010);
PAINT MONO (-3265 4010);
DISPLAY INVISIBLE (-3265 4010);
FORCEPROP 1 LASTPIN (-3275 4000) BN 3
J 0
(-3287 4008);
DISPLAY 0.489362 (-3287 4008);
PAINT GREEN (-3287 4008);
FORCEPROP 2 LAST CDS_LIB mstr_standard
J 0
(-3225 4000);
DISPLAY 0.723404 (-3225 4000);
PAINT MONO (-3225 4000);
DISPLAY INVISIBLE (-3225 4000);
FORCEPROP 1 LAST BODY_TYPE PLUMBING
J 0
(-3225 4050);
DISPLAY 0.872340 (-3225 4050);
PAINT GREEN (-3225 4050);
DISPLAY INVISIBLE (-3225 4050);
FORCEPROP 1 LAST HDL_TAP TRUE
J 0
(-2900 3875);
DISPLAY 0.872340 (-2900 3875);
DISPLAY INVISIBLE (-2900 3875);
FORCEPROP 1 LAST PATH I198
J 0
(-3227 4000);
DISPLAY 0.872340 (-3227 4000);
PAINT GREEN (-3227 4000);
DISPLAY INVISIBLE (-3227 4000);
FORCEADD TAP..1
(-3225 3950);
FORCEPROP 3 LASTPIN (-3275 3950) SIG_NAME M_I_CPU1_SB_DQ<4>
J 0
(-3265 3960);
DISPLAY 0.659574 (-3265 3960);
PAINT MONO (-3265 3960);
DISPLAY INVISIBLE (-3265 3960);
FORCEPROP 1 LASTPIN (-3275 3950) BN 4
J 0
(-3287 3958);
DISPLAY 0.489362 (-3287 3958);
PAINT GREEN (-3287 3958);
FORCEPROP 2 LAST CDS_LIB mstr_standard
J 0
(-3225 3950);
DISPLAY 0.723404 (-3225 3950);
PAINT MONO (-3225 3950);
DISPLAY INVISIBLE (-3225 3950);
FORCEPROP 1 LAST BODY_TYPE PLUMBING
J 0
(-3225 4000);
DISPLAY 0.872340 (-3225 4000);
PAINT GREEN (-3225 4000);
DISPLAY INVISIBLE (-3225 4000);
FORCEPROP 1 LAST HDL_TAP TRUE
J 0
(-2900 3825);
DISPLAY 0.872340 (-2900 3825);
DISPLAY INVISIBLE (-2900 3825);
FORCEPROP 1 LAST PATH I199
J 0
(-3227 3950);
DISPLAY 0.872340 (-3227 3950);
PAINT GREEN (-3227 3950);
DISPLAY INVISIBLE (-3227 3950);
FORCEADD TAP..1
(-3225 3900);
FORCEPROP 3 LASTPIN (-3275 3900) SIG_NAME M_I_CPU1_SB_DQ<5>
J 0
(-3265 3910);
DISPLAY 0.659574 (-3265 3910);
PAINT MONO (-3265 3910);
DISPLAY INVISIBLE (-3265 3910);
FORCEPROP 1 LASTPIN (-3275 3900) BN 5
J 0
(-3287 3908);
DISPLAY 0.489362 (-3287 3908);
PAINT GREEN (-3287 3908);
FORCEPROP 2 LAST CDS_LIB mstr_standard
J 0
(-3225 3900);
DISPLAY 0.723404 (-3225 3900);
PAINT MONO (-3225 3900);
DISPLAY INVISIBLE (-3225 3900);
FORCEPROP 1 LAST BODY_TYPE PLUMBING
J 0
(-3225 3950);
DISPLAY 0.872340 (-3225 3950);
PAINT GREEN (-3225 3950);
DISPLAY INVISIBLE (-3225 3950);
FORCEPROP 1 LAST HDL_TAP TRUE
J 0
(-2900 3775);
DISPLAY 0.872340 (-2900 3775);
DISPLAY INVISIBLE (-2900 3775);
FORCEPROP 1 LAST PATH I200
J 0
(-3227 3900);
DISPLAY 0.872340 (-3227 3900);
PAINT GREEN (-3227 3900);
DISPLAY INVISIBLE (-3227 3900);
FORCEADD TAP..1
(-3225 3850);
FORCEPROP 3 LASTPIN (-3275 3850) SIG_NAME M_I_CPU1_SB_DQ<6>
J 0
(-3265 3860);
DISPLAY 0.659574 (-3265 3860);
PAINT MONO (-3265 3860);
DISPLAY INVISIBLE (-3265 3860);
FORCEPROP 1 LASTPIN (-3275 3850) BN 6
J 0
(-3287 3858);
DISPLAY 0.489362 (-3287 3858);
PAINT GREEN (-3287 3858);
FORCEPROP 2 LAST CDS_LIB mstr_standard
J 0
(-3225 3850);
DISPLAY 0.723404 (-3225 3850);
PAINT MONO (-3225 3850);
DISPLAY INVISIBLE (-3225 3850);
FORCEPROP 1 LAST BODY_TYPE PLUMBING
J 0
(-3225 3900);
DISPLAY 0.872340 (-3225 3900);
PAINT GREEN (-3225 3900);
DISPLAY INVISIBLE (-3225 3900);
FORCEPROP 1 LAST HDL_TAP TRUE
J 0
(-2900 3725);
DISPLAY 0.872340 (-2900 3725);
DISPLAY INVISIBLE (-2900 3725);
FORCEPROP 1 LAST PATH I201
J 0
(-3227 3850);
DISPLAY 0.872340 (-3227 3850);
PAINT GREEN (-3227 3850);
DISPLAY INVISIBLE (-3227 3850);
FORCEADD TAP..1
(-3225 3800);
FORCEPROP 3 LASTPIN (-3275 3800) SIG_NAME M_I_CPU1_SB_DQ<7>
J 0
(-3265 3810);
DISPLAY 0.659574 (-3265 3810);
PAINT MONO (-3265 3810);
DISPLAY INVISIBLE (-3265 3810);
FORCEPROP 1 LASTPIN (-3275 3800) BN 7
J 0
(-3287 3808);
DISPLAY 0.489362 (-3287 3808);
PAINT GREEN (-3287 3808);
FORCEPROP 2 LAST CDS_LIB mstr_standard
J 0
(-3225 3800);
DISPLAY 0.723404 (-3225 3800);
PAINT MONO (-3225 3800);
DISPLAY INVISIBLE (-3225 3800);
FORCEPROP 1 LAST BODY_TYPE PLUMBING
J 0
(-3225 3850);
DISPLAY 0.872340 (-3225 3850);
PAINT GREEN (-3225 3850);
DISPLAY INVISIBLE (-3225 3850);
FORCEPROP 1 LAST HDL_TAP TRUE
J 0
(-2900 3675);
DISPLAY 0.872340 (-2900 3675);
DISPLAY INVISIBLE (-2900 3675);
FORCEPROP 1 LAST PATH I202
J 0
(-3227 3800);
DISPLAY 0.872340 (-3227 3800);
PAINT GREEN (-3227 3800);
DISPLAY INVISIBLE (-3227 3800);
FORCEADD TAP..1
(-3225 3700);
FORCEPROP 3 LASTPIN (-3275 3700) SIG_NAME M_I_CPU1_SB_DQ<8>
J 0
(-3265 3710);
DISPLAY 0.659574 (-3265 3710);
PAINT MONO (-3265 3710);
DISPLAY INVISIBLE (-3265 3710);
FORCEPROP 1 LASTPIN (-3275 3700) BN 8
J 0
(-3287 3708);
DISPLAY 0.489362 (-3287 3708);
PAINT GREEN (-3287 3708);
FORCEPROP 2 LAST CDS_LIB mstr_standard
J 0
(-3225 3700);
DISPLAY 0.723404 (-3225 3700);
PAINT MONO (-3225 3700);
DISPLAY INVISIBLE (-3225 3700);
FORCEPROP 1 LAST BODY_TYPE PLUMBING
J 0
(-3225 3750);
DISPLAY 0.872340 (-3225 3750);
PAINT GREEN (-3225 3750);
DISPLAY INVISIBLE (-3225 3750);
FORCEPROP 1 LAST HDL_TAP TRUE
J 0
(-2900 3575);
DISPLAY 0.872340 (-2900 3575);
DISPLAY INVISIBLE (-2900 3575);
FORCEPROP 1 LAST PATH I203
J 0
(-3227 3700);
DISPLAY 0.872340 (-3227 3700);
PAINT GREEN (-3227 3700);
DISPLAY INVISIBLE (-3227 3700);
FORCEADD TAP..1
(-3225 3650);
FORCEPROP 3 LASTPIN (-3275 3650) SIG_NAME M_I_CPU1_SB_DQ<9>
J 0
(-3265 3660);
DISPLAY 0.659574 (-3265 3660);
PAINT MONO (-3265 3660);
DISPLAY INVISIBLE (-3265 3660);
FORCEPROP 1 LASTPIN (-3275 3650) BN 9
J 0
(-3287 3658);
DISPLAY 0.489362 (-3287 3658);
PAINT GREEN (-3287 3658);
FORCEPROP 2 LAST CDS_LIB mstr_standard
J 0
(-3225 3650);
DISPLAY 0.723404 (-3225 3650);
PAINT MONO (-3225 3650);
DISPLAY INVISIBLE (-3225 3650);
FORCEPROP 1 LAST BODY_TYPE PLUMBING
J 0
(-3225 3700);
DISPLAY 0.872340 (-3225 3700);
PAINT GREEN (-3225 3700);
DISPLAY INVISIBLE (-3225 3700);
FORCEPROP 1 LAST HDL_TAP TRUE
J 0
(-2900 3525);
DISPLAY 0.872340 (-2900 3525);
DISPLAY INVISIBLE (-2900 3525);
FORCEPROP 1 LAST PATH I204
J 0
(-3227 3650);
DISPLAY 0.872340 (-3227 3650);
PAINT GREEN (-3227 3650);
DISPLAY INVISIBLE (-3227 3650);
FORCEADD TAP..1
(-3225 3600);
FORCEPROP 3 LASTPIN (-3275 3600) SIG_NAME M_I_CPU1_SB_DQ<10>
J 0
(-3265 3610);
DISPLAY 0.659574 (-3265 3610);
PAINT MONO (-3265 3610);
DISPLAY INVISIBLE (-3265 3610);
FORCEPROP 1 LASTPIN (-3275 3600) BN 10
J 0
(-3287 3608);
DISPLAY 0.489362 (-3287 3608);
PAINT GREEN (-3287 3608);
FORCEPROP 2 LAST CDS_LIB mstr_standard
J 0
(-3225 3600);
DISPLAY 0.723404 (-3225 3600);
PAINT MONO (-3225 3600);
DISPLAY INVISIBLE (-3225 3600);
FORCEPROP 1 LAST BODY_TYPE PLUMBING
J 0
(-3225 3650);
DISPLAY 0.872340 (-3225 3650);
PAINT GREEN (-3225 3650);
DISPLAY INVISIBLE (-3225 3650);
FORCEPROP 1 LAST HDL_TAP TRUE
J 0
(-2900 3475);
DISPLAY 0.872340 (-2900 3475);
DISPLAY INVISIBLE (-2900 3475);
FORCEPROP 1 LAST PATH I205
J 0
(-3227 3600);
DISPLAY 0.872340 (-3227 3600);
PAINT GREEN (-3227 3600);
DISPLAY INVISIBLE (-3227 3600);
FORCEADD TAP..1
(-3225 3550);
FORCEPROP 3 LASTPIN (-3275 3550) SIG_NAME M_I_CPU1_SB_DQ<11>
J 0
(-3265 3560);
DISPLAY 0.659574 (-3265 3560);
PAINT MONO (-3265 3560);
DISPLAY INVISIBLE (-3265 3560);
FORCEPROP 1 LASTPIN (-3275 3550) BN 11
J 0
(-3287 3558);
DISPLAY 0.489362 (-3287 3558);
PAINT GREEN (-3287 3558);
FORCEPROP 2 LAST CDS_LIB mstr_standard
J 0
(-3225 3550);
DISPLAY 0.723404 (-3225 3550);
PAINT MONO (-3225 3550);
DISPLAY INVISIBLE (-3225 3550);
FORCEPROP 1 LAST BODY_TYPE PLUMBING
J 0
(-3225 3600);
DISPLAY 0.872340 (-3225 3600);
PAINT GREEN (-3225 3600);
DISPLAY INVISIBLE (-3225 3600);
FORCEPROP 1 LAST HDL_TAP TRUE
J 0
(-2900 3425);
DISPLAY 0.872340 (-2900 3425);
DISPLAY INVISIBLE (-2900 3425);
FORCEPROP 1 LAST PATH I206
J 0
(-3227 3550);
DISPLAY 0.872340 (-3227 3550);
PAINT GREEN (-3227 3550);
DISPLAY INVISIBLE (-3227 3550);
FORCEADD TAP..1
(-3225 3500);
FORCEPROP 3 LASTPIN (-3275 3500) SIG_NAME M_I_CPU1_SB_DQ<12>
J 0
(-3265 3510);
DISPLAY 0.659574 (-3265 3510);
PAINT MONO (-3265 3510);
DISPLAY INVISIBLE (-3265 3510);
FORCEPROP 1 LASTPIN (-3275 3500) BN 12
J 0
(-3287 3508);
DISPLAY 0.489362 (-3287 3508);
PAINT GREEN (-3287 3508);
FORCEPROP 2 LAST CDS_LIB mstr_standard
J 0
(-3225 3500);
DISPLAY 0.723404 (-3225 3500);
PAINT MONO (-3225 3500);
DISPLAY INVISIBLE (-3225 3500);
FORCEPROP 1 LAST BODY_TYPE PLUMBING
J 0
(-3225 3550);
DISPLAY 0.872340 (-3225 3550);
PAINT GREEN (-3225 3550);
DISPLAY INVISIBLE (-3225 3550);
FORCEPROP 1 LAST HDL_TAP TRUE
J 0
(-2900 3375);
DISPLAY 0.872340 (-2900 3375);
DISPLAY INVISIBLE (-2900 3375);
FORCEPROP 1 LAST PATH I207
J 0
(-3227 3500);
DISPLAY 0.872340 (-3227 3500);
PAINT GREEN (-3227 3500);
DISPLAY INVISIBLE (-3227 3500);
FORCEADD TAP..1
(-3225 3450);
FORCEPROP 3 LASTPIN (-3275 3450) SIG_NAME M_I_CPU1_SB_DQ<13>
J 0
(-3265 3460);
DISPLAY 0.659574 (-3265 3460);
PAINT MONO (-3265 3460);
DISPLAY INVISIBLE (-3265 3460);
FORCEPROP 1 LASTPIN (-3275 3450) BN 13
J 0
(-3287 3458);
DISPLAY 0.489362 (-3287 3458);
PAINT GREEN (-3287 3458);
FORCEPROP 2 LAST CDS_LIB mstr_standard
J 0
(-3225 3450);
DISPLAY 0.723404 (-3225 3450);
PAINT MONO (-3225 3450);
DISPLAY INVISIBLE (-3225 3450);
FORCEPROP 1 LAST BODY_TYPE PLUMBING
J 0
(-3225 3500);
DISPLAY 0.872340 (-3225 3500);
PAINT GREEN (-3225 3500);
DISPLAY INVISIBLE (-3225 3500);
FORCEPROP 1 LAST HDL_TAP TRUE
J 0
(-2900 3325);
DISPLAY 0.872340 (-2900 3325);
DISPLAY INVISIBLE (-2900 3325);
FORCEPROP 1 LAST PATH I208
J 0
(-3227 3450);
DISPLAY 0.872340 (-3227 3450);
PAINT GREEN (-3227 3450);
DISPLAY INVISIBLE (-3227 3450);
FORCEADD TAP..1
(-3225 3350);
FORCEPROP 3 LASTPIN (-3275 3350) SIG_NAME M_I_CPU1_SB_DQ<15>
J 0
(-3265 3360);
DISPLAY 0.659574 (-3265 3360);
PAINT MONO (-3265 3360);
DISPLAY INVISIBLE (-3265 3360);
FORCEPROP 1 LASTPIN (-3275 3350) BN 15
J 0
(-3287 3358);
DISPLAY 0.489362 (-3287 3358);
PAINT GREEN (-3287 3358);
FORCEPROP 2 LAST CDS_LIB mstr_standard
J 0
(-3225 3350);
DISPLAY 0.723404 (-3225 3350);
PAINT MONO (-3225 3350);
DISPLAY INVISIBLE (-3225 3350);
FORCEPROP 1 LAST BODY_TYPE PLUMBING
J 0
(-3225 3400);
DISPLAY 0.872340 (-3225 3400);
PAINT GREEN (-3225 3400);
DISPLAY INVISIBLE (-3225 3400);
FORCEPROP 1 LAST HDL_TAP TRUE
J 0
(-2900 3225);
DISPLAY 0.872340 (-2900 3225);
DISPLAY INVISIBLE (-2900 3225);
FORCEPROP 1 LAST PATH I209
J 0
(-3227 3350);
DISPLAY 0.872340 (-3227 3350);
PAINT GREEN (-3227 3350);
DISPLAY INVISIBLE (-3227 3350);
FORCEADD TAP..1
(-3225 3400);
FORCEPROP 3 LASTPIN (-3275 3400) SIG_NAME M_I_CPU1_SB_DQ<14>
J 0
(-3265 3410);
DISPLAY 0.659574 (-3265 3410);
PAINT MONO (-3265 3410);
DISPLAY INVISIBLE (-3265 3410);
FORCEPROP 1 LASTPIN (-3275 3400) BN 14
J 0
(-3287 3408);
DISPLAY 0.489362 (-3287 3408);
PAINT GREEN (-3287 3408);
FORCEPROP 2 LAST CDS_LIB mstr_standard
J 0
(-3225 3400);
DISPLAY 0.723404 (-3225 3400);
PAINT MONO (-3225 3400);
DISPLAY INVISIBLE (-3225 3400);
FORCEPROP 1 LAST BODY_TYPE PLUMBING
J 0
(-3225 3450);
DISPLAY 0.872340 (-3225 3450);
PAINT GREEN (-3225 3450);
DISPLAY INVISIBLE (-3225 3450);
FORCEPROP 1 LAST HDL_TAP TRUE
J 0
(-2900 3275);
DISPLAY 0.872340 (-2900 3275);
DISPLAY INVISIBLE (-2900 3275);
FORCEPROP 1 LAST PATH I210
J 0
(-3227 3400);
DISPLAY 0.872340 (-3227 3400);
PAINT GREEN (-3227 3400);
DISPLAY INVISIBLE (-3227 3400);
FORCEADD TAP..1
(-3225 3250);
FORCEPROP 3 LASTPIN (-3275 3250) SIG_NAME M_I_CPU1_SB_DQ<16>
J 0
(-3265 3260);
DISPLAY 0.659574 (-3265 3260);
PAINT MONO (-3265 3260);
DISPLAY INVISIBLE (-3265 3260);
FORCEPROP 1 LASTPIN (-3275 3250) BN 16
J 0
(-3287 3258);
DISPLAY 0.489362 (-3287 3258);
PAINT GREEN (-3287 3258);
FORCEPROP 2 LAST CDS_LIB mstr_standard
J 0
(-3225 3250);
DISPLAY 0.723404 (-3225 3250);
PAINT MONO (-3225 3250);
DISPLAY INVISIBLE (-3225 3250);
FORCEPROP 1 LAST BODY_TYPE PLUMBING
J 0
(-3225 3300);
DISPLAY 0.872340 (-3225 3300);
PAINT GREEN (-3225 3300);
DISPLAY INVISIBLE (-3225 3300);
FORCEPROP 1 LAST HDL_TAP TRUE
J 0
(-2900 3125);
DISPLAY 0.872340 (-2900 3125);
DISPLAY INVISIBLE (-2900 3125);
FORCEPROP 1 LAST PATH I211
J 0
(-3227 3250);
DISPLAY 0.872340 (-3227 3250);
PAINT GREEN (-3227 3250);
DISPLAY INVISIBLE (-3227 3250);
FORCEADD TAP..1
(-3225 3200);
FORCEPROP 3 LASTPIN (-3275 3200) SIG_NAME M_I_CPU1_SB_DQ<17>
J 0
(-3265 3210);
DISPLAY 0.659574 (-3265 3210);
PAINT MONO (-3265 3210);
DISPLAY INVISIBLE (-3265 3210);
FORCEPROP 1 LASTPIN (-3275 3200) BN 17
J 0
(-3287 3208);
DISPLAY 0.489362 (-3287 3208);
PAINT GREEN (-3287 3208);
FORCEPROP 2 LAST CDS_LIB mstr_standard
J 0
(-3225 3200);
DISPLAY 0.723404 (-3225 3200);
PAINT MONO (-3225 3200);
DISPLAY INVISIBLE (-3225 3200);
FORCEPROP 1 LAST BODY_TYPE PLUMBING
J 0
(-3225 3250);
DISPLAY 0.872340 (-3225 3250);
PAINT GREEN (-3225 3250);
DISPLAY INVISIBLE (-3225 3250);
FORCEPROP 1 LAST HDL_TAP TRUE
J 0
(-2900 3075);
DISPLAY 0.872340 (-2900 3075);
DISPLAY INVISIBLE (-2900 3075);
FORCEPROP 1 LAST PATH I212
J 0
(-3227 3200);
DISPLAY 0.872340 (-3227 3200);
PAINT GREEN (-3227 3200);
DISPLAY INVISIBLE (-3227 3200);
FORCEADD TAP..1
(-3225 3150);
FORCEPROP 3 LASTPIN (-3275 3150) SIG_NAME M_I_CPU1_SB_DQ<18>
J 0
(-3265 3160);
DISPLAY 0.659574 (-3265 3160);
PAINT MONO (-3265 3160);
DISPLAY INVISIBLE (-3265 3160);
FORCEPROP 1 LASTPIN (-3275 3150) BN 18
J 0
(-3287 3158);
DISPLAY 0.489362 (-3287 3158);
PAINT GREEN (-3287 3158);
FORCEPROP 2 LAST CDS_LIB mstr_standard
J 0
(-3225 3150);
DISPLAY 0.723404 (-3225 3150);
PAINT MONO (-3225 3150);
DISPLAY INVISIBLE (-3225 3150);
FORCEPROP 1 LAST BODY_TYPE PLUMBING
J 0
(-3225 3200);
DISPLAY 0.872340 (-3225 3200);
PAINT GREEN (-3225 3200);
DISPLAY INVISIBLE (-3225 3200);
FORCEPROP 1 LAST HDL_TAP TRUE
J 0
(-2900 3025);
DISPLAY 0.872340 (-2900 3025);
DISPLAY INVISIBLE (-2900 3025);
FORCEPROP 1 LAST PATH I213
J 0
(-3227 3150);
DISPLAY 0.872340 (-3227 3150);
PAINT GREEN (-3227 3150);
DISPLAY INVISIBLE (-3227 3150);
FORCEADD TAP..1
(-3225 3100);
FORCEPROP 3 LASTPIN (-3275 3100) SIG_NAME M_I_CPU1_SB_DQ<19>
J 0
(-3265 3110);
DISPLAY 0.659574 (-3265 3110);
PAINT MONO (-3265 3110);
DISPLAY INVISIBLE (-3265 3110);
FORCEPROP 1 LASTPIN (-3275 3100) BN 19
J 0
(-3287 3108);
DISPLAY 0.489362 (-3287 3108);
PAINT GREEN (-3287 3108);
FORCEPROP 2 LAST CDS_LIB mstr_standard
J 0
(-3225 3100);
DISPLAY 0.723404 (-3225 3100);
PAINT MONO (-3225 3100);
DISPLAY INVISIBLE (-3225 3100);
FORCEPROP 1 LAST BODY_TYPE PLUMBING
J 0
(-3225 3150);
DISPLAY 0.872340 (-3225 3150);
PAINT GREEN (-3225 3150);
DISPLAY INVISIBLE (-3225 3150);
FORCEPROP 1 LAST HDL_TAP TRUE
J 0
(-2900 2975);
DISPLAY 0.872340 (-2900 2975);
DISPLAY INVISIBLE (-2900 2975);
FORCEPROP 1 LAST PATH I214
J 0
(-3227 3100);
DISPLAY 0.872340 (-3227 3100);
PAINT GREEN (-3227 3100);
DISPLAY INVISIBLE (-3227 3100);
FORCEADD TAP..1
(-3225 3000);
FORCEPROP 3 LASTPIN (-3275 3000) SIG_NAME M_I_CPU1_SB_DQ<21>
J 0
(-3265 3010);
DISPLAY 0.659574 (-3265 3010);
PAINT MONO (-3265 3010);
DISPLAY INVISIBLE (-3265 3010);
FORCEPROP 1 LASTPIN (-3275 3000) BN 21
J 0
(-3287 3008);
DISPLAY 0.489362 (-3287 3008);
PAINT GREEN (-3287 3008);
FORCEPROP 2 LAST CDS_LIB mstr_standard
J 0
(-3225 3000);
DISPLAY 0.723404 (-3225 3000);
PAINT MONO (-3225 3000);
DISPLAY INVISIBLE (-3225 3000);
FORCEPROP 1 LAST BODY_TYPE PLUMBING
J 0
(-3225 3050);
DISPLAY 0.872340 (-3225 3050);
PAINT GREEN (-3225 3050);
DISPLAY INVISIBLE (-3225 3050);
FORCEPROP 1 LAST HDL_TAP TRUE
J 0
(-2900 2875);
DISPLAY 0.872340 (-2900 2875);
DISPLAY INVISIBLE (-2900 2875);
FORCEPROP 1 LAST PATH I215
J 0
(-3227 3000);
DISPLAY 0.872340 (-3227 3000);
PAINT GREEN (-3227 3000);
DISPLAY INVISIBLE (-3227 3000);
FORCEADD TAP..1
(-3225 2900);
FORCEPROP 3 LASTPIN (-3275 2900) SIG_NAME M_I_CPU1_SB_DQ<23>
J 0
(-3265 2910);
DISPLAY 0.659574 (-3265 2910);
PAINT MONO (-3265 2910);
DISPLAY INVISIBLE (-3265 2910);
FORCEPROP 1 LASTPIN (-3275 2900) BN 23
J 0
(-3287 2908);
DISPLAY 0.489362 (-3287 2908);
PAINT GREEN (-3287 2908);
FORCEPROP 2 LAST CDS_LIB mstr_standard
J 0
(-3225 2900);
DISPLAY 0.723404 (-3225 2900);
PAINT MONO (-3225 2900);
DISPLAY INVISIBLE (-3225 2900);
FORCEPROP 1 LAST BODY_TYPE PLUMBING
J 0
(-3225 2950);
DISPLAY 0.872340 (-3225 2950);
PAINT GREEN (-3225 2950);
DISPLAY INVISIBLE (-3225 2950);
FORCEPROP 1 LAST HDL_TAP TRUE
J 0
(-2900 2775);
DISPLAY 0.872340 (-2900 2775);
DISPLAY INVISIBLE (-2900 2775);
FORCEPROP 1 LAST PATH I216
J 0
(-3227 2900);
DISPLAY 0.872340 (-3227 2900);
PAINT GREEN (-3227 2900);
DISPLAY INVISIBLE (-3227 2900);
FORCEADD TAP..1
(-3225 3050);
FORCEPROP 3 LASTPIN (-3275 3050) SIG_NAME M_I_CPU1_SB_DQ<20>
J 0
(-3265 3060);
DISPLAY 0.659574 (-3265 3060);
PAINT MONO (-3265 3060);
DISPLAY INVISIBLE (-3265 3060);
FORCEPROP 1 LASTPIN (-3275 3050) BN 20
J 0
(-3287 3058);
DISPLAY 0.489362 (-3287 3058);
PAINT GREEN (-3287 3058);
FORCEPROP 2 LAST CDS_LIB mstr_standard
J 0
(-3225 3050);
DISPLAY 0.723404 (-3225 3050);
PAINT MONO (-3225 3050);
DISPLAY INVISIBLE (-3225 3050);
FORCEPROP 1 LAST BODY_TYPE PLUMBING
J 0
(-3225 3100);
DISPLAY 0.872340 (-3225 3100);
PAINT GREEN (-3225 3100);
DISPLAY INVISIBLE (-3225 3100);
FORCEPROP 1 LAST HDL_TAP TRUE
J 0
(-2900 2925);
DISPLAY 0.872340 (-2900 2925);
DISPLAY INVISIBLE (-2900 2925);
FORCEPROP 1 LAST PATH I217
J 0
(-3227 3050);
DISPLAY 0.872340 (-3227 3050);
PAINT GREEN (-3227 3050);
DISPLAY INVISIBLE (-3227 3050);
FORCEADD TAP..1
(-3225 2950);
FORCEPROP 3 LASTPIN (-3275 2950) SIG_NAME M_I_CPU1_SB_DQ<22>
J 0
(-3265 2960);
DISPLAY 0.659574 (-3265 2960);
PAINT MONO (-3265 2960);
DISPLAY INVISIBLE (-3265 2960);
FORCEPROP 1 LASTPIN (-3275 2950) BN 22
J 0
(-3287 2958);
DISPLAY 0.489362 (-3287 2958);
PAINT GREEN (-3287 2958);
FORCEPROP 2 LAST CDS_LIB mstr_standard
J 0
(-3225 2950);
DISPLAY 0.723404 (-3225 2950);
PAINT MONO (-3225 2950);
DISPLAY INVISIBLE (-3225 2950);
FORCEPROP 1 LAST BODY_TYPE PLUMBING
J 0
(-3225 3000);
DISPLAY 0.872340 (-3225 3000);
PAINT GREEN (-3225 3000);
DISPLAY INVISIBLE (-3225 3000);
FORCEPROP 1 LAST HDL_TAP TRUE
J 0
(-2900 2825);
DISPLAY 0.872340 (-2900 2825);
DISPLAY INVISIBLE (-2900 2825);
FORCEPROP 1 LAST PATH I218
J 0
(-3227 2950);
DISPLAY 0.872340 (-3227 2950);
PAINT GREEN (-3227 2950);
DISPLAY INVISIBLE (-3227 2950);
FORCEADD TAP..1
(-3225 2800);
FORCEPROP 3 LASTPIN (-3275 2800) SIG_NAME M_I_CPU1_SB_DQ<24>
J 0
(-3265 2810);
DISPLAY 0.659574 (-3265 2810);
PAINT MONO (-3265 2810);
DISPLAY INVISIBLE (-3265 2810);
FORCEPROP 1 LASTPIN (-3275 2800) BN 24
J 0
(-3287 2808);
DISPLAY 0.489362 (-3287 2808);
PAINT GREEN (-3287 2808);
FORCEPROP 2 LAST CDS_LIB mstr_standard
J 0
(-3225 2800);
DISPLAY 0.723404 (-3225 2800);
PAINT MONO (-3225 2800);
DISPLAY INVISIBLE (-3225 2800);
FORCEPROP 1 LAST BODY_TYPE PLUMBING
J 0
(-3225 2850);
DISPLAY 0.872340 (-3225 2850);
PAINT GREEN (-3225 2850);
DISPLAY INVISIBLE (-3225 2850);
FORCEPROP 1 LAST HDL_TAP TRUE
J 0
(-2900 2675);
DISPLAY 0.872340 (-2900 2675);
DISPLAY INVISIBLE (-2900 2675);
FORCEPROP 1 LAST PATH I219
J 0
(-3227 2800);
DISPLAY 0.872340 (-3227 2800);
PAINT GREEN (-3227 2800);
DISPLAY INVISIBLE (-3227 2800);
FORCEADD TAP..1
(-3225 2750);
FORCEPROP 3 LASTPIN (-3275 2750) SIG_NAME M_I_CPU1_SB_DQ<25>
J 0
(-3265 2760);
DISPLAY 0.659574 (-3265 2760);
PAINT MONO (-3265 2760);
DISPLAY INVISIBLE (-3265 2760);
FORCEPROP 1 LASTPIN (-3275 2750) BN 25
J 0
(-3287 2758);
DISPLAY 0.489362 (-3287 2758);
PAINT GREEN (-3287 2758);
FORCEPROP 2 LAST CDS_LIB mstr_standard
J 0
(-3225 2750);
DISPLAY 0.723404 (-3225 2750);
PAINT MONO (-3225 2750);
DISPLAY INVISIBLE (-3225 2750);
FORCEPROP 1 LAST BODY_TYPE PLUMBING
J 0
(-3225 2800);
DISPLAY 0.872340 (-3225 2800);
PAINT GREEN (-3225 2800);
DISPLAY INVISIBLE (-3225 2800);
FORCEPROP 1 LAST HDL_TAP TRUE
J 0
(-2900 2625);
DISPLAY 0.872340 (-2900 2625);
DISPLAY INVISIBLE (-2900 2625);
FORCEPROP 1 LAST PATH I220
J 0
(-3227 2750);
DISPLAY 0.872340 (-3227 2750);
PAINT GREEN (-3227 2750);
DISPLAY INVISIBLE (-3227 2750);
FORCEADD TAP..1
(-3225 2700);
FORCEPROP 3 LASTPIN (-3275 2700) SIG_NAME M_I_CPU1_SB_DQ<26>
J 0
(-3265 2710);
DISPLAY 0.659574 (-3265 2710);
PAINT MONO (-3265 2710);
DISPLAY INVISIBLE (-3265 2710);
FORCEPROP 1 LASTPIN (-3275 2700) BN 26
J 0
(-3287 2708);
DISPLAY 0.489362 (-3287 2708);
PAINT GREEN (-3287 2708);
FORCEPROP 2 LAST CDS_LIB mstr_standard
J 0
(-3225 2700);
DISPLAY 0.723404 (-3225 2700);
PAINT MONO (-3225 2700);
DISPLAY INVISIBLE (-3225 2700);
FORCEPROP 1 LAST BODY_TYPE PLUMBING
J 0
(-3225 2750);
DISPLAY 0.872340 (-3225 2750);
PAINT GREEN (-3225 2750);
DISPLAY INVISIBLE (-3225 2750);
FORCEPROP 1 LAST HDL_TAP TRUE
J 0
(-2900 2575);
DISPLAY 0.872340 (-2900 2575);
DISPLAY INVISIBLE (-2900 2575);
FORCEPROP 1 LAST PATH I221
J 0
(-3227 2700);
DISPLAY 0.872340 (-3227 2700);
PAINT GREEN (-3227 2700);
DISPLAY INVISIBLE (-3227 2700);
FORCEADD TAP..1
(-3225 2600);
FORCEPROP 3 LASTPIN (-3275 2600) SIG_NAME M_I_CPU1_SB_DQ<28>
J 0
(-3265 2610);
DISPLAY 0.659574 (-3265 2610);
PAINT MONO (-3265 2610);
DISPLAY INVISIBLE (-3265 2610);
FORCEPROP 1 LASTPIN (-3275 2600) BN 28
J 0
(-3287 2608);
DISPLAY 0.489362 (-3287 2608);
PAINT GREEN (-3287 2608);
FORCEPROP 2 LAST CDS_LIB mstr_standard
J 0
(-3225 2600);
DISPLAY 0.723404 (-3225 2600);
PAINT MONO (-3225 2600);
DISPLAY INVISIBLE (-3225 2600);
FORCEPROP 1 LAST BODY_TYPE PLUMBING
J 0
(-3225 2650);
DISPLAY 0.872340 (-3225 2650);
PAINT GREEN (-3225 2650);
DISPLAY INVISIBLE (-3225 2650);
FORCEPROP 1 LAST HDL_TAP TRUE
J 0
(-2900 2475);
DISPLAY 0.872340 (-2900 2475);
DISPLAY INVISIBLE (-2900 2475);
FORCEPROP 1 LAST PATH I222
J 0
(-3227 2600);
DISPLAY 0.872340 (-3227 2600);
PAINT GREEN (-3227 2600);
DISPLAY INVISIBLE (-3227 2600);
FORCEADD TAP..1
(-3225 2650);
FORCEPROP 3 LASTPIN (-3275 2650) SIG_NAME M_I_CPU1_SB_DQ<27>
J 0
(-3265 2660);
DISPLAY 0.659574 (-3265 2660);
PAINT MONO (-3265 2660);
DISPLAY INVISIBLE (-3265 2660);
FORCEPROP 1 LASTPIN (-3275 2650) BN 27
J 0
(-3287 2658);
DISPLAY 0.489362 (-3287 2658);
PAINT GREEN (-3287 2658);
FORCEPROP 2 LAST CDS_LIB mstr_standard
J 0
(-3225 2650);
DISPLAY 0.723404 (-3225 2650);
PAINT MONO (-3225 2650);
DISPLAY INVISIBLE (-3225 2650);
FORCEPROP 1 LAST BODY_TYPE PLUMBING
J 0
(-3225 2700);
DISPLAY 0.872340 (-3225 2700);
PAINT GREEN (-3225 2700);
DISPLAY INVISIBLE (-3225 2700);
FORCEPROP 1 LAST HDL_TAP TRUE
J 0
(-2900 2525);
DISPLAY 0.872340 (-2900 2525);
DISPLAY INVISIBLE (-2900 2525);
FORCEPROP 1 LAST PATH I223
J 0
(-3227 2650);
DISPLAY 0.872340 (-3227 2650);
PAINT GREEN (-3227 2650);
DISPLAY INVISIBLE (-3227 2650);
FORCEADD TAP..1
(-3225 2500);
FORCEPROP 3 LASTPIN (-3275 2500) SIG_NAME M_I_CPU1_SB_DQ<30>
J 0
(-3265 2510);
DISPLAY 0.659574 (-3265 2510);
PAINT MONO (-3265 2510);
DISPLAY INVISIBLE (-3265 2510);
FORCEPROP 1 LASTPIN (-3275 2500) BN 30
J 0
(-3287 2508);
DISPLAY 0.489362 (-3287 2508);
PAINT GREEN (-3287 2508);
FORCEPROP 2 LAST CDS_LIB mstr_standard
J 0
(-3225 2500);
DISPLAY 0.723404 (-3225 2500);
PAINT MONO (-3225 2500);
DISPLAY INVISIBLE (-3225 2500);
FORCEPROP 1 LAST BODY_TYPE PLUMBING
J 0
(-3225 2550);
DISPLAY 0.872340 (-3225 2550);
PAINT GREEN (-3225 2550);
DISPLAY INVISIBLE (-3225 2550);
FORCEPROP 1 LAST HDL_TAP TRUE
J 0
(-2900 2375);
DISPLAY 0.872340 (-2900 2375);
DISPLAY INVISIBLE (-2900 2375);
FORCEPROP 1 LAST PATH I224
J 0
(-3227 2500);
DISPLAY 0.872340 (-3227 2500);
PAINT GREEN (-3227 2500);
DISPLAY INVISIBLE (-3227 2500);
FORCEADD TAP..1
(-3225 2550);
FORCEPROP 3 LASTPIN (-3275 2550) SIG_NAME M_I_CPU1_SB_DQ<29>
J 0
(-3265 2560);
DISPLAY 0.659574 (-3265 2560);
PAINT MONO (-3265 2560);
DISPLAY INVISIBLE (-3265 2560);
FORCEPROP 1 LASTPIN (-3275 2550) BN 29
J 0
(-3287 2558);
DISPLAY 0.489362 (-3287 2558);
PAINT GREEN (-3287 2558);
FORCEPROP 2 LAST CDS_LIB mstr_standard
J 0
(-3225 2550);
DISPLAY 0.723404 (-3225 2550);
PAINT MONO (-3225 2550);
DISPLAY INVISIBLE (-3225 2550);
FORCEPROP 1 LAST BODY_TYPE PLUMBING
J 0
(-3225 2600);
DISPLAY 0.872340 (-3225 2600);
PAINT GREEN (-3225 2600);
DISPLAY INVISIBLE (-3225 2600);
FORCEPROP 1 LAST HDL_TAP TRUE
J 0
(-2900 2425);
DISPLAY 0.872340 (-2900 2425);
DISPLAY INVISIBLE (-2900 2425);
FORCEPROP 1 LAST PATH I225
J 0
(-3227 2550);
DISPLAY 0.872340 (-3227 2550);
PAINT GREEN (-3227 2550);
DISPLAY INVISIBLE (-3227 2550);
FORCEADD TAP..1
(-3225 2450);
FORCEPROP 3 LASTPIN (-3275 2450) SIG_NAME M_I_CPU1_SB_DQ<31>
J 0
(-3265 2460);
DISPLAY 0.659574 (-3265 2460);
PAINT MONO (-3265 2460);
DISPLAY INVISIBLE (-3265 2460);
FORCEPROP 1 LASTPIN (-3275 2450) BN 31
J 0
(-3287 2458);
DISPLAY 0.489362 (-3287 2458);
PAINT GREEN (-3287 2458);
FORCEPROP 2 LAST CDS_LIB mstr_standard
J 0
(-3225 2450);
DISPLAY 0.723404 (-3225 2450);
PAINT MONO (-3225 2450);
DISPLAY INVISIBLE (-3225 2450);
FORCEPROP 1 LAST BODY_TYPE PLUMBING
J 0
(-3225 2500);
DISPLAY 0.872340 (-3225 2500);
PAINT GREEN (-3225 2500);
DISPLAY INVISIBLE (-3225 2500);
FORCEPROP 1 LAST HDL_TAP TRUE
J 0
(-2900 2325);
DISPLAY 0.872340 (-2900 2325);
DISPLAY INVISIBLE (-2900 2325);
FORCEPROP 1 LAST PATH I226
J 0
(-3227 2450);
DISPLAY 0.872340 (-3227 2450);
PAINT GREEN (-3227 2450);
DISPLAY INVISIBLE (-3227 2450);
FORCEADD TAP..1
(-3225 2350);
FORCEPROP 3 LASTPIN (-3275 2350) SIG_NAME M_I_CPU1_SA_CB<0>
J 0
(-3265 2360);
DISPLAY 0.659574 (-3265 2360);
PAINT MONO (-3265 2360);
DISPLAY INVISIBLE (-3265 2360);
FORCEPROP 1 LASTPIN (-3275 2350) BN 0
J 0
(-3287 2358);
DISPLAY 0.489362 (-3287 2358);
PAINT GREEN (-3287 2358);
FORCEPROP 2 LAST CDS_LIB mstr_standard
J 2
(-3225 2350);
DISPLAY 0.723404 (-3225 2350);
PAINT MONO (-3225 2350);
DISPLAY INVISIBLE (-3225 2350);
FORCEPROP 1 LAST BODY_TYPE PLUMBING
J 0
(-3225 2400);
DISPLAY 0.872340 (-3225 2400);
PAINT GREEN (-3225 2400);
DISPLAY INVISIBLE (-3225 2400);
FORCEPROP 1 LAST HDL_TAP TRUE
J 0
(-2900 2225);
DISPLAY 0.872340 (-2900 2225);
DISPLAY INVISIBLE (-2900 2225);
FORCEPROP 1 LAST PATH I227
J 0
(-3227 2350);
DISPLAY 0.872340 (-3227 2350);
PAINT GREEN (-3227 2350);
DISPLAY INVISIBLE (-3227 2350);
FORCEADD TAP..1
(-3225 2300);
FORCEPROP 3 LASTPIN (-3275 2300) SIG_NAME M_I_CPU1_SA_CB<1>
J 0
(-3265 2310);
DISPLAY 0.659574 (-3265 2310);
PAINT MONO (-3265 2310);
DISPLAY INVISIBLE (-3265 2310);
FORCEPROP 1 LASTPIN (-3275 2300) BN 1
J 0
(-3287 2308);
DISPLAY 0.489362 (-3287 2308);
PAINT GREEN (-3287 2308);
FORCEPROP 2 LAST CDS_LIB mstr_standard
J 2
(-3225 2300);
DISPLAY 0.723404 (-3225 2300);
PAINT MONO (-3225 2300);
DISPLAY INVISIBLE (-3225 2300);
FORCEPROP 1 LAST BODY_TYPE PLUMBING
J 0
(-3225 2350);
DISPLAY 0.872340 (-3225 2350);
PAINT GREEN (-3225 2350);
DISPLAY INVISIBLE (-3225 2350);
FORCEPROP 1 LAST HDL_TAP TRUE
J 0
(-2900 2175);
DISPLAY 0.872340 (-2900 2175);
DISPLAY INVISIBLE (-2900 2175);
FORCEPROP 1 LAST PATH I228
J 0
(-3227 2300);
DISPLAY 0.872340 (-3227 2300);
PAINT GREEN (-3227 2300);
DISPLAY INVISIBLE (-3227 2300);
FORCEADD TAP..1
(-3225 2200);
FORCEPROP 3 LASTPIN (-3275 2200) SIG_NAME M_I_CPU1_SA_CB<3>
J 0
(-3265 2210);
DISPLAY 0.659574 (-3265 2210);
PAINT MONO (-3265 2210);
DISPLAY INVISIBLE (-3265 2210);
FORCEPROP 1 LASTPIN (-3275 2200) BN 3
J 0
(-3287 2208);
DISPLAY 0.489362 (-3287 2208);
PAINT GREEN (-3287 2208);
FORCEPROP 2 LAST CDS_LIB mstr_standard
J 2
(-3225 2200);
DISPLAY 0.723404 (-3225 2200);
PAINT MONO (-3225 2200);
DISPLAY INVISIBLE (-3225 2200);
FORCEPROP 1 LAST BODY_TYPE PLUMBING
J 0
(-3225 2250);
DISPLAY 0.872340 (-3225 2250);
PAINT GREEN (-3225 2250);
DISPLAY INVISIBLE (-3225 2250);
FORCEPROP 1 LAST HDL_TAP TRUE
J 0
(-2900 2075);
DISPLAY 0.872340 (-2900 2075);
DISPLAY INVISIBLE (-2900 2075);
FORCEPROP 1 LAST PATH I229
J 0
(-3227 2200);
DISPLAY 0.872340 (-3227 2200);
PAINT GREEN (-3227 2200);
DISPLAY INVISIBLE (-3227 2200);
FORCEADD TAP..1
(-3225 2250);
FORCEPROP 3 LASTPIN (-3275 2250) SIG_NAME M_I_CPU1_SA_CB<2>
J 0
(-3265 2260);
DISPLAY 0.659574 (-3265 2260);
PAINT MONO (-3265 2260);
DISPLAY INVISIBLE (-3265 2260);
FORCEPROP 1 LASTPIN (-3275 2250) BN 2
J 0
(-3287 2258);
DISPLAY 0.489362 (-3287 2258);
PAINT GREEN (-3287 2258);
FORCEPROP 2 LAST CDS_LIB mstr_standard
J 2
(-3225 2250);
DISPLAY 0.723404 (-3225 2250);
PAINT MONO (-3225 2250);
DISPLAY INVISIBLE (-3225 2250);
FORCEPROP 1 LAST BODY_TYPE PLUMBING
J 0
(-3225 2300);
DISPLAY 0.872340 (-3225 2300);
PAINT GREEN (-3225 2300);
DISPLAY INVISIBLE (-3225 2300);
FORCEPROP 1 LAST HDL_TAP TRUE
J 0
(-2900 2125);
DISPLAY 0.872340 (-2900 2125);
DISPLAY INVISIBLE (-2900 2125);
FORCEPROP 1 LAST PATH I230
J 0
(-3227 2250);
DISPLAY 0.872340 (-3227 2250);
PAINT GREEN (-3227 2250);
DISPLAY INVISIBLE (-3227 2250);
FORCEADD TAP..1
(-3225 2050);
FORCEPROP 3 LASTPIN (-3275 2050) SIG_NAME M_I_CPU1_SA_CB<6>
J 0
(-3265 2060);
DISPLAY 0.659574 (-3265 2060);
PAINT MONO (-3265 2060);
DISPLAY INVISIBLE (-3265 2060);
FORCEPROP 1 LASTPIN (-3275 2050) BN 6
J 0
(-3287 2058);
DISPLAY 0.489362 (-3287 2058);
PAINT GREEN (-3287 2058);
FORCEPROP 2 LAST CDS_LIB mstr_standard
J 2
(-3225 2050);
DISPLAY 0.723404 (-3225 2050);
PAINT MONO (-3225 2050);
DISPLAY INVISIBLE (-3225 2050);
FORCEPROP 1 LAST BODY_TYPE PLUMBING
J 0
(-3225 2100);
DISPLAY 0.872340 (-3225 2100);
PAINT GREEN (-3225 2100);
DISPLAY INVISIBLE (-3225 2100);
FORCEPROP 1 LAST HDL_TAP TRUE
J 0
(-2900 1925);
DISPLAY 0.872340 (-2900 1925);
DISPLAY INVISIBLE (-2900 1925);
FORCEPROP 1 LAST PATH I231
J 0
(-3227 2050);
DISPLAY 0.872340 (-3227 2050);
PAINT GREEN (-3227 2050);
DISPLAY INVISIBLE (-3227 2050);
FORCEADD TAP..1
(-3225 2100);
FORCEPROP 3 LASTPIN (-3275 2100) SIG_NAME M_I_CPU1_SA_CB<5>
J 0
(-3265 2110);
DISPLAY 0.659574 (-3265 2110);
PAINT MONO (-3265 2110);
DISPLAY INVISIBLE (-3265 2110);
FORCEPROP 1 LASTPIN (-3275 2100) BN 5
J 0
(-3287 2108);
DISPLAY 0.489362 (-3287 2108);
PAINT GREEN (-3287 2108);
FORCEPROP 2 LAST CDS_LIB mstr_standard
J 2
(-3225 2100);
DISPLAY 0.723404 (-3225 2100);
PAINT MONO (-3225 2100);
DISPLAY INVISIBLE (-3225 2100);
FORCEPROP 1 LAST BODY_TYPE PLUMBING
J 0
(-3225 2150);
DISPLAY 0.872340 (-3225 2150);
PAINT GREEN (-3225 2150);
DISPLAY INVISIBLE (-3225 2150);
FORCEPROP 1 LAST HDL_TAP TRUE
J 0
(-2900 1975);
DISPLAY 0.872340 (-2900 1975);
DISPLAY INVISIBLE (-2900 1975);
FORCEPROP 1 LAST PATH I232
J 0
(-3227 2100);
DISPLAY 0.872340 (-3227 2100);
PAINT GREEN (-3227 2100);
DISPLAY INVISIBLE (-3227 2100);
FORCEADD TAP..1
(-3225 2150);
FORCEPROP 3 LASTPIN (-3275 2150) SIG_NAME M_I_CPU1_SA_CB<4>
J 0
(-3265 2160);
DISPLAY 0.659574 (-3265 2160);
PAINT MONO (-3265 2160);
DISPLAY INVISIBLE (-3265 2160);
FORCEPROP 1 LASTPIN (-3275 2150) BN 4
J 0
(-3287 2158);
DISPLAY 0.489362 (-3287 2158);
PAINT GREEN (-3287 2158);
FORCEPROP 2 LAST CDS_LIB mstr_standard
J 2
(-3225 2150);
DISPLAY 0.723404 (-3225 2150);
PAINT MONO (-3225 2150);
DISPLAY INVISIBLE (-3225 2150);
FORCEPROP 1 LAST BODY_TYPE PLUMBING
J 0
(-3225 2200);
DISPLAY 0.872340 (-3225 2200);
PAINT GREEN (-3225 2200);
DISPLAY INVISIBLE (-3225 2200);
FORCEPROP 1 LAST HDL_TAP TRUE
J 0
(-2900 2025);
DISPLAY 0.872340 (-2900 2025);
DISPLAY INVISIBLE (-2900 2025);
FORCEPROP 1 LAST PATH I233
J 0
(-3227 2150);
DISPLAY 0.872340 (-3227 2150);
PAINT GREEN (-3227 2150);
DISPLAY INVISIBLE (-3227 2150);
FORCEADD OFFPAGE..6
R 2
(-2625 1950);
FORCEPROP 2 LAST $XR0 106 
J 0
(-2411 1950);
DISPLAY 0.638298 (-2411 1950);
PAINT MONO (-2411 1950);
FORCEPROP 2 LAST CDS_LIB mstr_standard
J 2
(-2625 1950);
DISPLAY 0.723404 (-2625 1950);
PAINT MONO (-2625 1950);
DISPLAY INVISIBLE (-2625 1950);
FORCEPROP 1 LAST OFFPAGE TRUE
J 2
(-2950 1825);
DISPLAY 0.872340 (-2950 1825);
PAINT GREEN (-2950 1825);
DISPLAY INVISIBLE (-2950 1825);
FORCEPROP 1 LAST COMMENT_BODY TRUE
J 2
(-2725 1875);
DISPLAY 0.872340 (-2725 1875);
PAINT GREEN (-2725 1875);
DISPLAY INVISIBLE (-2725 1875);
FORCEPROP 2 LAST PATH I234
J 0
(-2400 2000);
DISPLAY 1.021277 (-2400 2000);
DISPLAY INVISIBLE (-2400 2000);
FORCEADD TAP..1
(-3225 1900);
FORCEPROP 3 LASTPIN (-3275 1900) SIG_NAME M_I_CPU1_SB_CB<0>
J 0
(-3265 1910);
DISPLAY 0.659574 (-3265 1910);
PAINT MONO (-3265 1910);
DISPLAY INVISIBLE (-3265 1910);
FORCEPROP 1 LASTPIN (-3275 1900) BN 0
J 0
(-3287 1908);
DISPLAY 0.489362 (-3287 1908);
PAINT GREEN (-3287 1908);
FORCEPROP 2 LAST CDS_LIB mstr_standard
J 2
(-3225 1900);
DISPLAY 0.723404 (-3225 1900);
PAINT MONO (-3225 1900);
DISPLAY INVISIBLE (-3225 1900);
FORCEPROP 1 LAST BODY_TYPE PLUMBING
J 0
(-3225 1950);
DISPLAY 0.872340 (-3225 1950);
PAINT GREEN (-3225 1950);
DISPLAY INVISIBLE (-3225 1950);
FORCEPROP 1 LAST HDL_TAP TRUE
J 0
(-2900 1775);
DISPLAY 0.872340 (-2900 1775);
DISPLAY INVISIBLE (-2900 1775);
FORCEPROP 1 LAST PATH I235
J 0
(-3227 1900);
DISPLAY 0.872340 (-3227 1900);
PAINT GREEN (-3227 1900);
DISPLAY INVISIBLE (-3227 1900);
FORCEADD TAP..1
(-3225 2000);
FORCEPROP 3 LASTPIN (-3275 2000) SIG_NAME M_I_CPU1_SA_CB<7>
J 0
(-3265 2010);
DISPLAY 0.659574 (-3265 2010);
PAINT MONO (-3265 2010);
DISPLAY INVISIBLE (-3265 2010);
FORCEPROP 1 LASTPIN (-3275 2000) BN 7
J 0
(-3287 2008);
DISPLAY 0.489362 (-3287 2008);
PAINT GREEN (-3287 2008);
FORCEPROP 2 LAST CDS_LIB mstr_standard
J 2
(-3225 2000);
DISPLAY 0.723404 (-3225 2000);
PAINT MONO (-3225 2000);
DISPLAY INVISIBLE (-3225 2000);
FORCEPROP 1 LAST BODY_TYPE PLUMBING
J 0
(-3225 2050);
DISPLAY 0.872340 (-3225 2050);
PAINT GREEN (-3225 2050);
DISPLAY INVISIBLE (-3225 2050);
FORCEPROP 1 LAST HDL_TAP TRUE
J 0
(-2900 1875);
DISPLAY 0.872340 (-2900 1875);
DISPLAY INVISIBLE (-2900 1875);
FORCEPROP 1 LAST PATH I236
J 0
(-3227 2000);
DISPLAY 0.872340 (-3227 2000);
PAINT GREEN (-3227 2000);
DISPLAY INVISIBLE (-3227 2000);
FORCEADD TAP..1
(-3225 1800);
FORCEPROP 3 LASTPIN (-3275 1800) SIG_NAME M_I_CPU1_SB_CB<2>
J 0
(-3265 1810);
DISPLAY 0.659574 (-3265 1810);
PAINT MONO (-3265 1810);
DISPLAY INVISIBLE (-3265 1810);
FORCEPROP 1 LASTPIN (-3275 1800) BN 2
J 0
(-3287 1808);
DISPLAY 0.489362 (-3287 1808);
PAINT GREEN (-3287 1808);
FORCEPROP 2 LAST CDS_LIB mstr_standard
J 2
(-3225 1800);
DISPLAY 0.723404 (-3225 1800);
PAINT MONO (-3225 1800);
DISPLAY INVISIBLE (-3225 1800);
FORCEPROP 1 LAST BODY_TYPE PLUMBING
J 0
(-3225 1850);
DISPLAY 0.872340 (-3225 1850);
PAINT GREEN (-3225 1850);
DISPLAY INVISIBLE (-3225 1850);
FORCEPROP 1 LAST HDL_TAP TRUE
J 0
(-2900 1675);
DISPLAY 0.872340 (-2900 1675);
DISPLAY INVISIBLE (-2900 1675);
FORCEPROP 1 LAST PATH I237
J 0
(-3227 1800);
DISPLAY 0.872340 (-3227 1800);
PAINT GREEN (-3227 1800);
DISPLAY INVISIBLE (-3227 1800);
FORCEADD TAP..1
(-3225 1850);
FORCEPROP 3 LASTPIN (-3275 1850) SIG_NAME M_I_CPU1_SB_CB<1>
J 0
(-3265 1860);
DISPLAY 0.659574 (-3265 1860);
PAINT MONO (-3265 1860);
DISPLAY INVISIBLE (-3265 1860);
FORCEPROP 1 LASTPIN (-3275 1850) BN 1
J 0
(-3287 1858);
DISPLAY 0.489362 (-3287 1858);
PAINT GREEN (-3287 1858);
FORCEPROP 2 LAST CDS_LIB mstr_standard
J 2
(-3225 1850);
DISPLAY 0.723404 (-3225 1850);
PAINT MONO (-3225 1850);
DISPLAY INVISIBLE (-3225 1850);
FORCEPROP 1 LAST BODY_TYPE PLUMBING
J 0
(-3225 1900);
DISPLAY 0.872340 (-3225 1900);
PAINT GREEN (-3225 1900);
DISPLAY INVISIBLE (-3225 1900);
FORCEPROP 1 LAST HDL_TAP TRUE
J 0
(-2900 1725);
DISPLAY 0.872340 (-2900 1725);
DISPLAY INVISIBLE (-2900 1725);
FORCEPROP 1 LAST PATH I238
J 0
(-3227 1850);
DISPLAY 0.872340 (-3227 1850);
PAINT GREEN (-3227 1850);
DISPLAY INVISIBLE (-3227 1850);
FORCEADD TAP..1
(-3225 1750);
FORCEPROP 3 LASTPIN (-3275 1750) SIG_NAME M_I_CPU1_SB_CB<3>
J 0
(-3265 1760);
DISPLAY 0.659574 (-3265 1760);
PAINT MONO (-3265 1760);
DISPLAY INVISIBLE (-3265 1760);
FORCEPROP 1 LASTPIN (-3275 1750) BN 3
J 0
(-3287 1758);
DISPLAY 0.489362 (-3287 1758);
PAINT GREEN (-3287 1758);
FORCEPROP 2 LAST CDS_LIB mstr_standard
J 2
(-3225 1750);
DISPLAY 0.723404 (-3225 1750);
PAINT MONO (-3225 1750);
DISPLAY INVISIBLE (-3225 1750);
FORCEPROP 1 LAST BODY_TYPE PLUMBING
J 0
(-3225 1800);
DISPLAY 0.872340 (-3225 1800);
PAINT GREEN (-3225 1800);
DISPLAY INVISIBLE (-3225 1800);
FORCEPROP 1 LAST HDL_TAP TRUE
J 0
(-2900 1625);
DISPLAY 0.872340 (-2900 1625);
DISPLAY INVISIBLE (-2900 1625);
FORCEPROP 1 LAST PATH I239
J 0
(-3227 1750);
DISPLAY 0.872340 (-3227 1750);
PAINT GREEN (-3227 1750);
DISPLAY INVISIBLE (-3227 1750);
FORCEADD TAP..1
(-3225 1700);
FORCEPROP 3 LASTPIN (-3275 1700) SIG_NAME M_I_CPU1_SB_CB<4>
J 0
(-3265 1710);
DISPLAY 0.659574 (-3265 1710);
PAINT MONO (-3265 1710);
DISPLAY INVISIBLE (-3265 1710);
FORCEPROP 1 LASTPIN (-3275 1700) BN 4
J 0
(-3287 1708);
DISPLAY 0.489362 (-3287 1708);
PAINT GREEN (-3287 1708);
FORCEPROP 2 LAST CDS_LIB mstr_standard
J 2
(-3225 1700);
DISPLAY 0.723404 (-3225 1700);
PAINT MONO (-3225 1700);
DISPLAY INVISIBLE (-3225 1700);
FORCEPROP 1 LAST BODY_TYPE PLUMBING
J 0
(-3225 1750);
DISPLAY 0.872340 (-3225 1750);
PAINT GREEN (-3225 1750);
DISPLAY INVISIBLE (-3225 1750);
FORCEPROP 1 LAST HDL_TAP TRUE
J 0
(-2900 1575);
DISPLAY 0.872340 (-2900 1575);
DISPLAY INVISIBLE (-2900 1575);
FORCEPROP 1 LAST PATH I240
J 0
(-3227 1700);
DISPLAY 0.872340 (-3227 1700);
PAINT GREEN (-3227 1700);
DISPLAY INVISIBLE (-3227 1700);
FORCEADD TAP..1
(-3225 1650);
FORCEPROP 3 LASTPIN (-3275 1650) SIG_NAME M_I_CPU1_SB_CB<5>
J 0
(-3265 1660);
DISPLAY 0.659574 (-3265 1660);
PAINT MONO (-3265 1660);
DISPLAY INVISIBLE (-3265 1660);
FORCEPROP 1 LASTPIN (-3275 1650) BN 5
J 0
(-3287 1658);
DISPLAY 0.489362 (-3287 1658);
PAINT GREEN (-3287 1658);
FORCEPROP 2 LAST CDS_LIB mstr_standard
J 2
(-3225 1650);
DISPLAY 0.723404 (-3225 1650);
PAINT MONO (-3225 1650);
DISPLAY INVISIBLE (-3225 1650);
FORCEPROP 1 LAST BODY_TYPE PLUMBING
J 0
(-3225 1700);
DISPLAY 0.872340 (-3225 1700);
PAINT GREEN (-3225 1700);
DISPLAY INVISIBLE (-3225 1700);
FORCEPROP 1 LAST HDL_TAP TRUE
J 0
(-2900 1525);
DISPLAY 0.872340 (-2900 1525);
DISPLAY INVISIBLE (-2900 1525);
FORCEPROP 1 LAST PATH I241
J 0
(-3227 1650);
DISPLAY 0.872340 (-3227 1650);
PAINT GREEN (-3227 1650);
DISPLAY INVISIBLE (-3227 1650);
FORCEADD TAP..1
(-3225 1550);
FORCEPROP 3 LASTPIN (-3275 1550) SIG_NAME M_I_CPU1_SB_CB<7>
J 0
(-3265 1560);
DISPLAY 0.659574 (-3265 1560);
PAINT MONO (-3265 1560);
DISPLAY INVISIBLE (-3265 1560);
FORCEPROP 1 LASTPIN (-3275 1550) BN 7
J 0
(-3287 1558);
DISPLAY 0.489362 (-3287 1558);
PAINT GREEN (-3287 1558);
FORCEPROP 2 LAST CDS_LIB mstr_standard
J 2
(-3225 1550);
DISPLAY 0.723404 (-3225 1550);
PAINT MONO (-3225 1550);
DISPLAY INVISIBLE (-3225 1550);
FORCEPROP 1 LAST BODY_TYPE PLUMBING
J 0
(-3225 1600);
DISPLAY 0.872340 (-3225 1600);
PAINT GREEN (-3225 1600);
DISPLAY INVISIBLE (-3225 1600);
FORCEPROP 1 LAST HDL_TAP TRUE
J 0
(-2900 1425);
DISPLAY 0.872340 (-2900 1425);
DISPLAY INVISIBLE (-2900 1425);
FORCEPROP 1 LAST PATH I242
J 0
(-3227 1550);
DISPLAY 0.872340 (-3227 1550);
PAINT GREEN (-3227 1550);
DISPLAY INVISIBLE (-3227 1550);
FORCEADD TAP..1
(-3225 1600);
FORCEPROP 3 LASTPIN (-3275 1600) SIG_NAME M_I_CPU1_SB_CB<6>
J 0
(-3265 1610);
DISPLAY 0.659574 (-3265 1610);
PAINT MONO (-3265 1610);
DISPLAY INVISIBLE (-3265 1610);
FORCEPROP 1 LASTPIN (-3275 1600) BN 6
J 0
(-3287 1608);
DISPLAY 0.489362 (-3287 1608);
PAINT GREEN (-3287 1608);
FORCEPROP 2 LAST CDS_LIB mstr_standard
J 2
(-3225 1600);
DISPLAY 0.723404 (-3225 1600);
PAINT MONO (-3225 1600);
DISPLAY INVISIBLE (-3225 1600);
FORCEPROP 1 LAST BODY_TYPE PLUMBING
J 0
(-3225 1650);
DISPLAY 0.872340 (-3225 1650);
PAINT GREEN (-3225 1650);
DISPLAY INVISIBLE (-3225 1650);
FORCEPROP 1 LAST HDL_TAP TRUE
J 0
(-2900 1475);
DISPLAY 0.872340 (-2900 1475);
DISPLAY INVISIBLE (-2900 1475);
FORCEPROP 1 LAST PATH I243
J 0
(-3227 1600);
DISPLAY 0.872340 (-3227 1600);
PAINT GREEN (-3227 1600);
DISPLAY INVISIBLE (-3227 1600);
FORCEADD TAP..1
R 2
(-5650 5950);
FORCEPROP 3 LASTPIN (-5600 5950) SIG_NAME M_I_CPU1_SA_DQS_DP<0>
J 0
(-5590 5960);
DISPLAY 0.659574 (-5590 5960);
PAINT MONO (-5590 5960);
DISPLAY INVISIBLE (-5590 5960);
FORCEPROP 1 LASTPIN (-5600 5950) BN 0
J 2
(-5588 5958);
DISPLAY 0.489362 (-5588 5958);
PAINT GREEN (-5588 5958);
FORCEPROP 2 LAST CDS_LIB mstr_standard
J 2
(-5650 5950);
DISPLAY 0.723404 (-5650 5950);
PAINT MONO (-5650 5950);
DISPLAY INVISIBLE (-5650 5950);
FORCEPROP 1 LAST BODY_TYPE PLUMBING
J 2
(-5650 6000);
DISPLAY 0.872340 (-5650 6000);
PAINT GREEN (-5650 6000);
DISPLAY INVISIBLE (-5650 6000);
FORCEPROP 1 LAST HDL_TAP TRUE
J 2
(-5975 5825);
DISPLAY 0.872340 (-5975 5825);
DISPLAY INVISIBLE (-5975 5825);
FORCEPROP 1 LAST PATH I244
J 2
(-5648 5950);
DISPLAY 0.872340 (-5648 5950);
PAINT GREEN (-5648 5950);
DISPLAY INVISIBLE (-5648 5950);
FORCEADD TAP..1
R 2
(-5650 5850);
FORCEPROP 3 LASTPIN (-5600 5850) SIG_NAME M_I_CPU1_SA_DQS_DP<1>
J 0
(-5590 5860);
DISPLAY 0.659574 (-5590 5860);
PAINT MONO (-5590 5860);
DISPLAY INVISIBLE (-5590 5860);
FORCEPROP 1 LASTPIN (-5600 5850) BN 1
J 2
(-5588 5858);
DISPLAY 0.489362 (-5588 5858);
PAINT GREEN (-5588 5858);
FORCEPROP 2 LAST CDS_LIB mstr_standard
J 2
(-5650 5850);
DISPLAY 0.723404 (-5650 5850);
PAINT MONO (-5650 5850);
DISPLAY INVISIBLE (-5650 5850);
FORCEPROP 1 LAST BODY_TYPE PLUMBING
J 2
(-5650 5900);
DISPLAY 0.872340 (-5650 5900);
PAINT GREEN (-5650 5900);
DISPLAY INVISIBLE (-5650 5900);
FORCEPROP 1 LAST HDL_TAP TRUE
J 2
(-5975 5725);
DISPLAY 0.872340 (-5975 5725);
DISPLAY INVISIBLE (-5975 5725);
FORCEPROP 1 LAST PATH I245
J 2
(-5648 5850);
DISPLAY 0.872340 (-5648 5850);
PAINT GREEN (-5648 5850);
DISPLAY INVISIBLE (-5648 5850);
FORCEADD TAP..1
R 2
(-5650 5750);
FORCEPROP 3 LASTPIN (-5600 5750) SIG_NAME M_I_CPU1_SA_DQS_DP<2>
J 0
(-5590 5760);
DISPLAY 0.659574 (-5590 5760);
PAINT MONO (-5590 5760);
DISPLAY INVISIBLE (-5590 5760);
FORCEPROP 1 LASTPIN (-5600 5750) BN 2
J 2
(-5588 5758);
DISPLAY 0.489362 (-5588 5758);
PAINT GREEN (-5588 5758);
FORCEPROP 2 LAST CDS_LIB mstr_standard
J 2
(-5650 5750);
DISPLAY 0.723404 (-5650 5750);
PAINT MONO (-5650 5750);
DISPLAY INVISIBLE (-5650 5750);
FORCEPROP 1 LAST BODY_TYPE PLUMBING
J 2
(-5650 5800);
DISPLAY 0.872340 (-5650 5800);
PAINT GREEN (-5650 5800);
DISPLAY INVISIBLE (-5650 5800);
FORCEPROP 1 LAST HDL_TAP TRUE
J 2
(-5975 5625);
DISPLAY 0.872340 (-5975 5625);
DISPLAY INVISIBLE (-5975 5625);
FORCEPROP 1 LAST PATH I246
J 2
(-5648 5750);
DISPLAY 0.872340 (-5648 5750);
PAINT GREEN (-5648 5750);
DISPLAY INVISIBLE (-5648 5750);
FORCEADD TAP..1
R 2
(-5650 5650);
FORCEPROP 3 LASTPIN (-5600 5650) SIG_NAME M_I_CPU1_SA_DQS_DP<3>
J 0
(-5590 5660);
DISPLAY 0.659574 (-5590 5660);
PAINT MONO (-5590 5660);
DISPLAY INVISIBLE (-5590 5660);
FORCEPROP 1 LASTPIN (-5600 5650) BN 3
J 2
(-5588 5658);
DISPLAY 0.489362 (-5588 5658);
PAINT GREEN (-5588 5658);
FORCEPROP 2 LAST CDS_LIB mstr_standard
J 2
(-5650 5650);
DISPLAY 0.723404 (-5650 5650);
PAINT MONO (-5650 5650);
DISPLAY INVISIBLE (-5650 5650);
FORCEPROP 1 LAST BODY_TYPE PLUMBING
J 2
(-5650 5700);
DISPLAY 0.872340 (-5650 5700);
PAINT GREEN (-5650 5700);
DISPLAY INVISIBLE (-5650 5700);
FORCEPROP 1 LAST HDL_TAP TRUE
J 2
(-5975 5525);
DISPLAY 0.872340 (-5975 5525);
DISPLAY INVISIBLE (-5975 5525);
FORCEPROP 1 LAST PATH I247
J 2
(-5648 5650);
DISPLAY 0.872340 (-5648 5650);
PAINT GREEN (-5648 5650);
DISPLAY INVISIBLE (-5648 5650);
FORCEADD TAP..1
R 2
(-5650 5450);
FORCEPROP 3 LASTPIN (-5600 5450) SIG_NAME M_I_CPU1_SA_DQS_DP<5>
J 0
(-5590 5460);
DISPLAY 0.659574 (-5590 5460);
PAINT MONO (-5590 5460);
DISPLAY INVISIBLE (-5590 5460);
FORCEPROP 1 LASTPIN (-5600 5450) BN 5
J 2
(-5588 5458);
DISPLAY 0.489362 (-5588 5458);
PAINT GREEN (-5588 5458);
FORCEPROP 2 LAST CDS_LIB mstr_standard
J 2
(-5650 5450);
DISPLAY 0.723404 (-5650 5450);
PAINT MONO (-5650 5450);
DISPLAY INVISIBLE (-5650 5450);
FORCEPROP 1 LAST BODY_TYPE PLUMBING
J 2
(-5650 5500);
DISPLAY 0.872340 (-5650 5500);
PAINT GREEN (-5650 5500);
DISPLAY INVISIBLE (-5650 5500);
FORCEPROP 1 LAST HDL_TAP TRUE
J 2
(-5975 5325);
DISPLAY 0.872340 (-5975 5325);
DISPLAY INVISIBLE (-5975 5325);
FORCEPROP 1 LAST PATH I248
J 2
(-5648 5450);
DISPLAY 0.872340 (-5648 5450);
PAINT GREEN (-5648 5450);
DISPLAY INVISIBLE (-5648 5450);
FORCEADD TAP..1
R 2
(-5650 5550);
FORCEPROP 3 LASTPIN (-5600 5550) SIG_NAME M_I_CPU1_SA_DQS_DP<4>
J 0
(-5590 5560);
DISPLAY 0.659574 (-5590 5560);
PAINT MONO (-5590 5560);
DISPLAY INVISIBLE (-5590 5560);
FORCEPROP 1 LASTPIN (-5600 5550) BN 4
J 2
(-5588 5558);
DISPLAY 0.489362 (-5588 5558);
PAINT GREEN (-5588 5558);
FORCEPROP 2 LAST CDS_LIB mstr_standard
J 2
(-5650 5550);
DISPLAY 0.723404 (-5650 5550);
PAINT MONO (-5650 5550);
DISPLAY INVISIBLE (-5650 5550);
FORCEPROP 1 LAST BODY_TYPE PLUMBING
J 2
(-5650 5600);
DISPLAY 0.872340 (-5650 5600);
PAINT GREEN (-5650 5600);
DISPLAY INVISIBLE (-5650 5600);
FORCEPROP 1 LAST HDL_TAP TRUE
J 2
(-5975 5425);
DISPLAY 0.872340 (-5975 5425);
DISPLAY INVISIBLE (-5975 5425);
FORCEPROP 1 LAST PATH I249
J 2
(-5648 5550);
DISPLAY 0.872340 (-5648 5550);
PAINT GREEN (-5648 5550);
DISPLAY INVISIBLE (-5648 5550);
FORCEADD TAP..1
R 2
(-5650 5350);
FORCEPROP 3 LASTPIN (-5600 5350) SIG_NAME M_I_CPU1_SA_DQS_DP<6>
J 0
(-5590 5360);
DISPLAY 0.659574 (-5590 5360);
PAINT MONO (-5590 5360);
DISPLAY INVISIBLE (-5590 5360);
FORCEPROP 1 LASTPIN (-5600 5350) BN 6
J 2
(-5588 5358);
DISPLAY 0.489362 (-5588 5358);
PAINT GREEN (-5588 5358);
FORCEPROP 2 LAST CDS_LIB mstr_standard
J 2
(-5650 5350);
DISPLAY 0.723404 (-5650 5350);
PAINT MONO (-5650 5350);
DISPLAY INVISIBLE (-5650 5350);
FORCEPROP 1 LAST BODY_TYPE PLUMBING
J 2
(-5650 5400);
DISPLAY 0.872340 (-5650 5400);
PAINT GREEN (-5650 5400);
DISPLAY INVISIBLE (-5650 5400);
FORCEPROP 1 LAST HDL_TAP TRUE
J 2
(-5975 5225);
DISPLAY 0.872340 (-5975 5225);
DISPLAY INVISIBLE (-5975 5225);
FORCEPROP 1 LAST PATH I250
J 2
(-5648 5350);
DISPLAY 0.872340 (-5648 5350);
PAINT GREEN (-5648 5350);
DISPLAY INVISIBLE (-5648 5350);
FORCEADD TAP..1
R 2
(-5650 5250);
FORCEPROP 3 LASTPIN (-5600 5250) SIG_NAME M_I_CPU1_SA_DQS_DP<7>
J 0
(-5590 5260);
DISPLAY 0.659574 (-5590 5260);
PAINT MONO (-5590 5260);
DISPLAY INVISIBLE (-5590 5260);
FORCEPROP 1 LASTPIN (-5600 5250) BN 7
J 2
(-5588 5258);
DISPLAY 0.489362 (-5588 5258);
PAINT GREEN (-5588 5258);
FORCEPROP 2 LAST CDS_LIB mstr_standard
J 2
(-5650 5250);
DISPLAY 0.723404 (-5650 5250);
PAINT MONO (-5650 5250);
DISPLAY INVISIBLE (-5650 5250);
FORCEPROP 1 LAST BODY_TYPE PLUMBING
J 2
(-5650 5300);
DISPLAY 0.872340 (-5650 5300);
PAINT GREEN (-5650 5300);
DISPLAY INVISIBLE (-5650 5300);
FORCEPROP 1 LAST HDL_TAP TRUE
J 2
(-5975 5125);
DISPLAY 0.872340 (-5975 5125);
DISPLAY INVISIBLE (-5975 5125);
FORCEPROP 1 LAST PATH I251
J 2
(-5648 5250);
DISPLAY 0.872340 (-5648 5250);
PAINT GREEN (-5648 5250);
DISPLAY INVISIBLE (-5648 5250);
FORCEADD TAP..1
R 2
(-5650 5150);
FORCEPROP 3 LASTPIN (-5600 5150) SIG_NAME M_I_CPU1_SA_DQS_DP<8>
J 0
(-5590 5160);
DISPLAY 0.659574 (-5590 5160);
PAINT MONO (-5590 5160);
DISPLAY INVISIBLE (-5590 5160);
FORCEPROP 1 LASTPIN (-5600 5150) BN 8
J 2
(-5588 5158);
DISPLAY 0.489362 (-5588 5158);
PAINT GREEN (-5588 5158);
FORCEPROP 2 LAST CDS_LIB mstr_standard
J 2
(-5650 5150);
DISPLAY 0.723404 (-5650 5150);
PAINT MONO (-5650 5150);
DISPLAY INVISIBLE (-5650 5150);
FORCEPROP 1 LAST BODY_TYPE PLUMBING
J 2
(-5650 5200);
DISPLAY 0.872340 (-5650 5200);
PAINT GREEN (-5650 5200);
DISPLAY INVISIBLE (-5650 5200);
FORCEPROP 1 LAST HDL_TAP TRUE
J 2
(-5975 5025);
DISPLAY 0.872340 (-5975 5025);
DISPLAY INVISIBLE (-5975 5025);
FORCEPROP 1 LAST PATH I252
J 2
(-5648 5150);
DISPLAY 0.872340 (-5648 5150);
PAINT GREEN (-5648 5150);
DISPLAY INVISIBLE (-5648 5150);
FORCEADD TAP..1
R 2
(-5850 5900);
FORCEPROP 3 LASTPIN (-5800 5900) SIG_NAME M_I_CPU1_SA_DQS_DN<0>
J 0
(-5790 5910);
DISPLAY 0.659574 (-5790 5910);
PAINT MONO (-5790 5910);
DISPLAY INVISIBLE (-5790 5910);
FORCEPROP 1 LASTPIN (-5800 5900) BN 0
J 2
(-5788 5908);
DISPLAY 0.489362 (-5788 5908);
PAINT GREEN (-5788 5908);
FORCEPROP 2 LAST CDS_LIB mstr_standard
J 2
(-5850 5900);
DISPLAY 0.723404 (-5850 5900);
PAINT MONO (-5850 5900);
DISPLAY INVISIBLE (-5850 5900);
FORCEPROP 1 LAST BODY_TYPE PLUMBING
J 2
(-5850 5950);
DISPLAY 0.872340 (-5850 5950);
PAINT GREEN (-5850 5950);
DISPLAY INVISIBLE (-5850 5950);
FORCEPROP 1 LAST HDL_TAP TRUE
J 2
(-6175 5775);
DISPLAY 0.872340 (-6175 5775);
DISPLAY INVISIBLE (-6175 5775);
FORCEPROP 1 LAST PATH I253
J 2
(-5848 5900);
DISPLAY 0.872340 (-5848 5900);
PAINT GREEN (-5848 5900);
DISPLAY INVISIBLE (-5848 5900);
FORCEADD TAP..1
R 2
(-5850 5700);
FORCEPROP 3 LASTPIN (-5800 5700) SIG_NAME M_I_CPU1_SA_DQS_DN<2>
J 0
(-5790 5710);
DISPLAY 0.659574 (-5790 5710);
PAINT MONO (-5790 5710);
DISPLAY INVISIBLE (-5790 5710);
FORCEPROP 1 LASTPIN (-5800 5700) BN 2
J 2
(-5788 5708);
DISPLAY 0.489362 (-5788 5708);
PAINT GREEN (-5788 5708);
FORCEPROP 2 LAST CDS_LIB mstr_standard
J 2
(-5850 5700);
DISPLAY 0.723404 (-5850 5700);
PAINT MONO (-5850 5700);
DISPLAY INVISIBLE (-5850 5700);
FORCEPROP 1 LAST BODY_TYPE PLUMBING
J 2
(-5850 5750);
DISPLAY 0.872340 (-5850 5750);
PAINT GREEN (-5850 5750);
DISPLAY INVISIBLE (-5850 5750);
FORCEPROP 1 LAST HDL_TAP TRUE
J 2
(-6175 5575);
DISPLAY 0.872340 (-6175 5575);
DISPLAY INVISIBLE (-6175 5575);
FORCEPROP 1 LAST PATH I254
J 2
(-5848 5700);
DISPLAY 0.872340 (-5848 5700);
PAINT GREEN (-5848 5700);
DISPLAY INVISIBLE (-5848 5700);
FORCEADD TAP..1
R 2
(-5850 5800);
FORCEPROP 3 LASTPIN (-5800 5800) SIG_NAME M_I_CPU1_SA_DQS_DN<1>
J 0
(-5790 5810);
DISPLAY 0.659574 (-5790 5810);
PAINT MONO (-5790 5810);
DISPLAY INVISIBLE (-5790 5810);
FORCEPROP 1 LASTPIN (-5800 5800) BN 1
J 2
(-5788 5808);
DISPLAY 0.489362 (-5788 5808);
PAINT GREEN (-5788 5808);
FORCEPROP 2 LAST CDS_LIB mstr_standard
J 2
(-5850 5800);
DISPLAY 0.723404 (-5850 5800);
PAINT MONO (-5850 5800);
DISPLAY INVISIBLE (-5850 5800);
FORCEPROP 1 LAST BODY_TYPE PLUMBING
J 2
(-5850 5850);
DISPLAY 0.872340 (-5850 5850);
PAINT GREEN (-5850 5850);
DISPLAY INVISIBLE (-5850 5850);
FORCEPROP 1 LAST HDL_TAP TRUE
J 2
(-6175 5675);
DISPLAY 0.872340 (-6175 5675);
DISPLAY INVISIBLE (-6175 5675);
FORCEPROP 1 LAST PATH I255
J 2
(-5848 5800);
DISPLAY 0.872340 (-5848 5800);
PAINT GREEN (-5848 5800);
DISPLAY INVISIBLE (-5848 5800);
FORCEADD TAP..1
R 2
(-5850 5400);
FORCEPROP 3 LASTPIN (-5800 5400) SIG_NAME M_I_CPU1_SA_DQS_DN<5>
J 0
(-5790 5410);
DISPLAY 0.659574 (-5790 5410);
PAINT MONO (-5790 5410);
DISPLAY INVISIBLE (-5790 5410);
FORCEPROP 1 LASTPIN (-5800 5400) BN 5
J 2
(-5788 5408);
DISPLAY 0.489362 (-5788 5408);
PAINT GREEN (-5788 5408);
FORCEPROP 2 LAST CDS_LIB mstr_standard
J 2
(-5850 5400);
DISPLAY 0.723404 (-5850 5400);
PAINT MONO (-5850 5400);
DISPLAY INVISIBLE (-5850 5400);
FORCEPROP 1 LAST BODY_TYPE PLUMBING
J 2
(-5850 5450);
DISPLAY 0.872340 (-5850 5450);
PAINT GREEN (-5850 5450);
DISPLAY INVISIBLE (-5850 5450);
FORCEPROP 1 LAST HDL_TAP TRUE
J 2
(-6175 5275);
DISPLAY 0.872340 (-6175 5275);
DISPLAY INVISIBLE (-6175 5275);
FORCEPROP 1 LAST PATH I256
J 2
(-5848 5400);
DISPLAY 0.872340 (-5848 5400);
PAINT GREEN (-5848 5400);
DISPLAY INVISIBLE (-5848 5400);
FORCEADD TAP..1
R 2
(-5850 5600);
FORCEPROP 3 LASTPIN (-5800 5600) SIG_NAME M_I_CPU1_SA_DQS_DN<3>
J 0
(-5790 5610);
DISPLAY 0.659574 (-5790 5610);
PAINT MONO (-5790 5610);
DISPLAY INVISIBLE (-5790 5610);
FORCEPROP 1 LASTPIN (-5800 5600) BN 3
J 2
(-5788 5608);
DISPLAY 0.489362 (-5788 5608);
PAINT GREEN (-5788 5608);
FORCEPROP 2 LAST CDS_LIB mstr_standard
J 2
(-5850 5600);
DISPLAY 0.723404 (-5850 5600);
PAINT MONO (-5850 5600);
DISPLAY INVISIBLE (-5850 5600);
FORCEPROP 1 LAST BODY_TYPE PLUMBING
J 2
(-5850 5650);
DISPLAY 0.872340 (-5850 5650);
PAINT GREEN (-5850 5650);
DISPLAY INVISIBLE (-5850 5650);
FORCEPROP 1 LAST HDL_TAP TRUE
J 2
(-6175 5475);
DISPLAY 0.872340 (-6175 5475);
DISPLAY INVISIBLE (-6175 5475);
FORCEPROP 1 LAST PATH I257
J 2
(-5848 5600);
DISPLAY 0.872340 (-5848 5600);
PAINT GREEN (-5848 5600);
DISPLAY INVISIBLE (-5848 5600);
FORCEADD TAP..1
R 2
(-5850 5500);
FORCEPROP 3 LASTPIN (-5800 5500) SIG_NAME M_I_CPU1_SA_DQS_DN<4>
J 0
(-5790 5510);
DISPLAY 0.659574 (-5790 5510);
PAINT MONO (-5790 5510);
DISPLAY INVISIBLE (-5790 5510);
FORCEPROP 1 LASTPIN (-5800 5500) BN 4
J 2
(-5788 5508);
DISPLAY 0.489362 (-5788 5508);
PAINT GREEN (-5788 5508);
FORCEPROP 2 LAST CDS_LIB mstr_standard
J 2
(-5850 5500);
DISPLAY 0.723404 (-5850 5500);
PAINT MONO (-5850 5500);
DISPLAY INVISIBLE (-5850 5500);
FORCEPROP 1 LAST BODY_TYPE PLUMBING
J 2
(-5850 5550);
DISPLAY 0.872340 (-5850 5550);
PAINT GREEN (-5850 5550);
DISPLAY INVISIBLE (-5850 5550);
FORCEPROP 1 LAST HDL_TAP TRUE
J 2
(-6175 5375);
DISPLAY 0.872340 (-6175 5375);
DISPLAY INVISIBLE (-6175 5375);
FORCEPROP 1 LAST PATH I258
J 2
(-5848 5500);
DISPLAY 0.872340 (-5848 5500);
PAINT GREEN (-5848 5500);
DISPLAY INVISIBLE (-5848 5500);
FORCEADD TAP..1
R 2
(-5850 5200);
FORCEPROP 3 LASTPIN (-5800 5200) SIG_NAME M_I_CPU1_SA_DQS_DN<7>
J 0
(-5790 5210);
DISPLAY 0.659574 (-5790 5210);
PAINT MONO (-5790 5210);
DISPLAY INVISIBLE (-5790 5210);
FORCEPROP 1 LASTPIN (-5800 5200) BN 7
J 2
(-5788 5208);
DISPLAY 0.489362 (-5788 5208);
PAINT GREEN (-5788 5208);
FORCEPROP 2 LAST CDS_LIB mstr_standard
J 2
(-5850 5200);
DISPLAY 0.723404 (-5850 5200);
PAINT MONO (-5850 5200);
DISPLAY INVISIBLE (-5850 5200);
FORCEPROP 1 LAST BODY_TYPE PLUMBING
J 2
(-5850 5250);
DISPLAY 0.872340 (-5850 5250);
PAINT GREEN (-5850 5250);
DISPLAY INVISIBLE (-5850 5250);
FORCEPROP 1 LAST HDL_TAP TRUE
J 2
(-6175 5075);
DISPLAY 0.872340 (-6175 5075);
DISPLAY INVISIBLE (-6175 5075);
FORCEPROP 1 LAST PATH I259
J 2
(-5848 5200);
DISPLAY 0.872340 (-5848 5200);
PAINT GREEN (-5848 5200);
DISPLAY INVISIBLE (-5848 5200);
FORCEADD TAP..1
R 2
(-5850 5300);
FORCEPROP 3 LASTPIN (-5800 5300) SIG_NAME M_I_CPU1_SA_DQS_DN<6>
J 0
(-5790 5310);
DISPLAY 0.659574 (-5790 5310);
PAINT MONO (-5790 5310);
DISPLAY INVISIBLE (-5790 5310);
FORCEPROP 1 LASTPIN (-5800 5300) BN 6
J 2
(-5788 5308);
DISPLAY 0.489362 (-5788 5308);
PAINT GREEN (-5788 5308);
FORCEPROP 2 LAST CDS_LIB mstr_standard
J 2
(-5850 5300);
DISPLAY 0.723404 (-5850 5300);
PAINT MONO (-5850 5300);
DISPLAY INVISIBLE (-5850 5300);
FORCEPROP 1 LAST BODY_TYPE PLUMBING
J 2
(-5850 5350);
DISPLAY 0.872340 (-5850 5350);
PAINT GREEN (-5850 5350);
DISPLAY INVISIBLE (-5850 5350);
FORCEPROP 1 LAST HDL_TAP TRUE
J 2
(-6175 5175);
DISPLAY 0.872340 (-6175 5175);
DISPLAY INVISIBLE (-6175 5175);
FORCEPROP 1 LAST PATH I260
J 2
(-5848 5300);
DISPLAY 0.872340 (-5848 5300);
PAINT GREEN (-5848 5300);
DISPLAY INVISIBLE (-5848 5300);
FORCEADD TAP..1
R 2
(-5650 4900);
FORCEPROP 3 LASTPIN (-5600 4900) SIG_NAME M_I_CPU1_SB_DQS_DP<0>
J 0
(-5590 4910);
DISPLAY 0.659574 (-5590 4910);
PAINT MONO (-5590 4910);
DISPLAY INVISIBLE (-5590 4910);
FORCEPROP 1 LASTPIN (-5600 4900) BN 0
J 2
(-5588 4908);
DISPLAY 0.489362 (-5588 4908);
PAINT GREEN (-5588 4908);
FORCEPROP 2 LAST CDS_LIB mstr_standard
J 2
(-5650 4900);
DISPLAY 0.723404 (-5650 4900);
PAINT MONO (-5650 4900);
DISPLAY INVISIBLE (-5650 4900);
FORCEPROP 1 LAST BODY_TYPE PLUMBING
J 2
(-5650 4950);
DISPLAY 0.872340 (-5650 4950);
PAINT GREEN (-5650 4950);
DISPLAY INVISIBLE (-5650 4950);
FORCEPROP 1 LAST HDL_TAP TRUE
J 2
(-5975 4775);
DISPLAY 0.872340 (-5975 4775);
DISPLAY INVISIBLE (-5975 4775);
FORCEPROP 1 LAST PATH I261
J 2
(-5648 4900);
DISPLAY 0.872340 (-5648 4900);
PAINT GREEN (-5648 4900);
DISPLAY INVISIBLE (-5648 4900);
FORCEADD TAP..1
R 2
(-5650 5050);
FORCEPROP 3 LASTPIN (-5600 5050) SIG_NAME M_I_CPU1_SA_DQS_DP<9>
J 0
(-5590 5060);
DISPLAY 0.659574 (-5590 5060);
PAINT MONO (-5590 5060);
DISPLAY INVISIBLE (-5590 5060);
FORCEPROP 1 LASTPIN (-5600 5050) BN 9
J 2
(-5588 5058);
DISPLAY 0.489362 (-5588 5058);
PAINT GREEN (-5588 5058);
FORCEPROP 2 LAST CDS_LIB mstr_standard
J 2
(-5650 5050);
DISPLAY 0.723404 (-5650 5050);
PAINT MONO (-5650 5050);
DISPLAY INVISIBLE (-5650 5050);
FORCEPROP 1 LAST BODY_TYPE PLUMBING
J 2
(-5650 5100);
DISPLAY 0.872340 (-5650 5100);
PAINT GREEN (-5650 5100);
DISPLAY INVISIBLE (-5650 5100);
FORCEPROP 1 LAST HDL_TAP TRUE
J 2
(-5975 4925);
DISPLAY 0.872340 (-5975 4925);
DISPLAY INVISIBLE (-5975 4925);
FORCEPROP 1 LAST PATH I262
J 2
(-5648 5050);
DISPLAY 0.872340 (-5648 5050);
PAINT GREEN (-5648 5050);
DISPLAY INVISIBLE (-5648 5050);
FORCEADD TAP..1
R 2
(-5650 4800);
FORCEPROP 3 LASTPIN (-5600 4800) SIG_NAME M_I_CPU1_SB_DQS_DP<1>
J 0
(-5590 4810);
DISPLAY 0.659574 (-5590 4810);
PAINT MONO (-5590 4810);
DISPLAY INVISIBLE (-5590 4810);
FORCEPROP 1 LASTPIN (-5600 4800) BN 1
J 2
(-5588 4808);
DISPLAY 0.489362 (-5588 4808);
PAINT GREEN (-5588 4808);
FORCEPROP 2 LAST CDS_LIB mstr_standard
J 2
(-5650 4800);
DISPLAY 0.723404 (-5650 4800);
PAINT MONO (-5650 4800);
DISPLAY INVISIBLE (-5650 4800);
FORCEPROP 1 LAST BODY_TYPE PLUMBING
J 2
(-5650 4850);
DISPLAY 0.872340 (-5650 4850);
PAINT GREEN (-5650 4850);
DISPLAY INVISIBLE (-5650 4850);
FORCEPROP 1 LAST HDL_TAP TRUE
J 2
(-5975 4675);
DISPLAY 0.872340 (-5975 4675);
DISPLAY INVISIBLE (-5975 4675);
FORCEPROP 1 LAST PATH I263
J 2
(-5648 4800);
DISPLAY 0.872340 (-5648 4800);
PAINT GREEN (-5648 4800);
DISPLAY INVISIBLE (-5648 4800);
FORCEADD TAP..1
R 2
(-5650 4700);
FORCEPROP 3 LASTPIN (-5600 4700) SIG_NAME M_I_CPU1_SB_DQS_DP<2>
J 0
(-5590 4710);
DISPLAY 0.659574 (-5590 4710);
PAINT MONO (-5590 4710);
DISPLAY INVISIBLE (-5590 4710);
FORCEPROP 1 LASTPIN (-5600 4700) BN 2
J 2
(-5588 4708);
DISPLAY 0.489362 (-5588 4708);
PAINT GREEN (-5588 4708);
FORCEPROP 2 LAST CDS_LIB mstr_standard
J 2
(-5650 4700);
DISPLAY 0.723404 (-5650 4700);
PAINT MONO (-5650 4700);
DISPLAY INVISIBLE (-5650 4700);
FORCEPROP 1 LAST BODY_TYPE PLUMBING
J 2
(-5650 4750);
DISPLAY 0.872340 (-5650 4750);
PAINT GREEN (-5650 4750);
DISPLAY INVISIBLE (-5650 4750);
FORCEPROP 1 LAST HDL_TAP TRUE
J 2
(-5975 4575);
DISPLAY 0.872340 (-5975 4575);
DISPLAY INVISIBLE (-5975 4575);
FORCEPROP 1 LAST PATH I264
J 2
(-5648 4700);
DISPLAY 0.872340 (-5648 4700);
PAINT GREEN (-5648 4700);
DISPLAY INVISIBLE (-5648 4700);
FORCEADD TAP..1
R 2
(-5650 4400);
FORCEPROP 3 LASTPIN (-5600 4400) SIG_NAME M_I_CPU1_SB_DQS_DP<5>
J 0
(-5590 4410);
DISPLAY 0.659574 (-5590 4410);
PAINT MONO (-5590 4410);
DISPLAY INVISIBLE (-5590 4410);
FORCEPROP 1 LASTPIN (-5600 4400) BN 5
J 2
(-5588 4408);
DISPLAY 0.489362 (-5588 4408);
PAINT GREEN (-5588 4408);
FORCEPROP 2 LAST CDS_LIB mstr_standard
J 2
(-5650 4400);
DISPLAY 0.723404 (-5650 4400);
PAINT MONO (-5650 4400);
DISPLAY INVISIBLE (-5650 4400);
FORCEPROP 1 LAST BODY_TYPE PLUMBING
J 2
(-5650 4450);
DISPLAY 0.872340 (-5650 4450);
PAINT GREEN (-5650 4450);
DISPLAY INVISIBLE (-5650 4450);
FORCEPROP 1 LAST HDL_TAP TRUE
J 2
(-5975 4275);
DISPLAY 0.872340 (-5975 4275);
DISPLAY INVISIBLE (-5975 4275);
FORCEPROP 1 LAST PATH I265
J 2
(-5648 4400);
DISPLAY 0.872340 (-5648 4400);
PAINT GREEN (-5648 4400);
DISPLAY INVISIBLE (-5648 4400);
FORCEADD TAP..1
R 2
(-5650 4600);
FORCEPROP 3 LASTPIN (-5600 4600) SIG_NAME M_I_CPU1_SB_DQS_DP<3>
J 0
(-5590 4610);
DISPLAY 0.659574 (-5590 4610);
PAINT MONO (-5590 4610);
DISPLAY INVISIBLE (-5590 4610);
FORCEPROP 1 LASTPIN (-5600 4600) BN 3
J 2
(-5588 4608);
DISPLAY 0.489362 (-5588 4608);
PAINT GREEN (-5588 4608);
FORCEPROP 2 LAST CDS_LIB mstr_standard
J 2
(-5650 4600);
DISPLAY 0.723404 (-5650 4600);
PAINT MONO (-5650 4600);
DISPLAY INVISIBLE (-5650 4600);
FORCEPROP 1 LAST BODY_TYPE PLUMBING
J 2
(-5650 4650);
DISPLAY 0.872340 (-5650 4650);
PAINT GREEN (-5650 4650);
DISPLAY INVISIBLE (-5650 4650);
FORCEPROP 1 LAST HDL_TAP TRUE
J 2
(-5975 4475);
DISPLAY 0.872340 (-5975 4475);
DISPLAY INVISIBLE (-5975 4475);
FORCEPROP 1 LAST PATH I266
J 2
(-5648 4600);
DISPLAY 0.872340 (-5648 4600);
PAINT GREEN (-5648 4600);
DISPLAY INVISIBLE (-5648 4600);
FORCEADD TAP..1
R 2
(-5650 4500);
FORCEPROP 3 LASTPIN (-5600 4500) SIG_NAME M_I_CPU1_SB_DQS_DP<4>
J 0
(-5590 4510);
DISPLAY 0.659574 (-5590 4510);
PAINT MONO (-5590 4510);
DISPLAY INVISIBLE (-5590 4510);
FORCEPROP 1 LASTPIN (-5600 4500) BN 4
J 2
(-5588 4508);
DISPLAY 0.489362 (-5588 4508);
PAINT GREEN (-5588 4508);
FORCEPROP 2 LAST CDS_LIB mstr_standard
J 2
(-5650 4500);
DISPLAY 0.723404 (-5650 4500);
PAINT MONO (-5650 4500);
DISPLAY INVISIBLE (-5650 4500);
FORCEPROP 1 LAST BODY_TYPE PLUMBING
J 2
(-5650 4550);
DISPLAY 0.872340 (-5650 4550);
PAINT GREEN (-5650 4550);
DISPLAY INVISIBLE (-5650 4550);
FORCEPROP 1 LAST HDL_TAP TRUE
J 2
(-5975 4375);
DISPLAY 0.872340 (-5975 4375);
DISPLAY INVISIBLE (-5975 4375);
FORCEPROP 1 LAST PATH I267
J 2
(-5648 4500);
DISPLAY 0.872340 (-5648 4500);
PAINT GREEN (-5648 4500);
DISPLAY INVISIBLE (-5648 4500);
FORCEADD TAP..1
R 2
(-5650 4300);
FORCEPROP 3 LASTPIN (-5600 4300) SIG_NAME M_I_CPU1_SB_DQS_DP<6>
J 0
(-5590 4310);
DISPLAY 0.659574 (-5590 4310);
PAINT MONO (-5590 4310);
DISPLAY INVISIBLE (-5590 4310);
FORCEPROP 1 LASTPIN (-5600 4300) BN 6
J 2
(-5588 4308);
DISPLAY 0.489362 (-5588 4308);
PAINT GREEN (-5588 4308);
FORCEPROP 2 LAST CDS_LIB mstr_standard
J 2
(-5650 4300);
DISPLAY 0.723404 (-5650 4300);
PAINT MONO (-5650 4300);
DISPLAY INVISIBLE (-5650 4300);
FORCEPROP 1 LAST BODY_TYPE PLUMBING
J 2
(-5650 4350);
DISPLAY 0.872340 (-5650 4350);
PAINT GREEN (-5650 4350);
DISPLAY INVISIBLE (-5650 4350);
FORCEPROP 1 LAST HDL_TAP TRUE
J 2
(-5975 4175);
DISPLAY 0.872340 (-5975 4175);
DISPLAY INVISIBLE (-5975 4175);
FORCEPROP 1 LAST PATH I268
J 2
(-5648 4300);
DISPLAY 0.872340 (-5648 4300);
PAINT GREEN (-5648 4300);
DISPLAY INVISIBLE (-5648 4300);
FORCEADD TAP..1
R 2
(-5650 4200);
FORCEPROP 3 LASTPIN (-5600 4200) SIG_NAME M_I_CPU1_SB_DQS_DP<7>
J 0
(-5590 4210);
DISPLAY 0.659574 (-5590 4210);
PAINT MONO (-5590 4210);
DISPLAY INVISIBLE (-5590 4210);
FORCEPROP 1 LASTPIN (-5600 4200) BN 7
J 2
(-5588 4208);
DISPLAY 0.489362 (-5588 4208);
PAINT GREEN (-5588 4208);
FORCEPROP 2 LAST CDS_LIB mstr_standard
J 2
(-5650 4200);
DISPLAY 0.723404 (-5650 4200);
PAINT MONO (-5650 4200);
DISPLAY INVISIBLE (-5650 4200);
FORCEPROP 1 LAST BODY_TYPE PLUMBING
J 2
(-5650 4250);
DISPLAY 0.872340 (-5650 4250);
PAINT GREEN (-5650 4250);
DISPLAY INVISIBLE (-5650 4250);
FORCEPROP 1 LAST HDL_TAP TRUE
J 2
(-5975 4075);
DISPLAY 0.872340 (-5975 4075);
DISPLAY INVISIBLE (-5975 4075);
FORCEPROP 1 LAST PATH I269
J 2
(-5648 4200);
DISPLAY 0.872340 (-5648 4200);
PAINT GREEN (-5648 4200);
DISPLAY INVISIBLE (-5648 4200);
FORCEADD TAP..1
R 2
(-5650 4100);
FORCEPROP 3 LASTPIN (-5600 4100) SIG_NAME M_I_CPU1_SB_DQS_DP<8>
J 0
(-5590 4110);
DISPLAY 0.659574 (-5590 4110);
PAINT MONO (-5590 4110);
DISPLAY INVISIBLE (-5590 4110);
FORCEPROP 1 LASTPIN (-5600 4100) BN 8
J 2
(-5588 4108);
DISPLAY 0.489362 (-5588 4108);
PAINT GREEN (-5588 4108);
FORCEPROP 2 LAST CDS_LIB mstr_standard
J 2
(-5650 4100);
DISPLAY 0.723404 (-5650 4100);
PAINT MONO (-5650 4100);
DISPLAY INVISIBLE (-5650 4100);
FORCEPROP 1 LAST BODY_TYPE PLUMBING
J 2
(-5650 4150);
DISPLAY 0.872340 (-5650 4150);
PAINT GREEN (-5650 4150);
DISPLAY INVISIBLE (-5650 4150);
FORCEPROP 1 LAST HDL_TAP TRUE
J 2
(-5975 3975);
DISPLAY 0.872340 (-5975 3975);
DISPLAY INVISIBLE (-5975 3975);
FORCEPROP 1 LAST PATH I270
J 2
(-5648 4100);
DISPLAY 0.872340 (-5648 4100);
PAINT GREEN (-5648 4100);
DISPLAY INVISIBLE (-5648 4100);
FORCEADD TAP..1
R 2
(-5850 5100);
FORCEPROP 3 LASTPIN (-5800 5100) SIG_NAME M_I_CPU1_SA_DQS_DN<8>
J 0
(-5790 5110);
DISPLAY 0.659574 (-5790 5110);
PAINT MONO (-5790 5110);
DISPLAY INVISIBLE (-5790 5110);
FORCEPROP 1 LASTPIN (-5800 5100) BN 8
J 2
(-5788 5108);
DISPLAY 0.489362 (-5788 5108);
PAINT GREEN (-5788 5108);
FORCEPROP 2 LAST CDS_LIB mstr_standard
J 2
(-5850 5100);
DISPLAY 0.723404 (-5850 5100);
PAINT MONO (-5850 5100);
DISPLAY INVISIBLE (-5850 5100);
FORCEPROP 1 LAST BODY_TYPE PLUMBING
J 2
(-5850 5150);
DISPLAY 0.872340 (-5850 5150);
PAINT GREEN (-5850 5150);
DISPLAY INVISIBLE (-5850 5150);
FORCEPROP 1 LAST HDL_TAP TRUE
J 2
(-6175 4975);
DISPLAY 0.872340 (-6175 4975);
DISPLAY INVISIBLE (-6175 4975);
FORCEPROP 1 LAST PATH I271
J 2
(-5848 5100);
DISPLAY 0.872340 (-5848 5100);
PAINT GREEN (-5848 5100);
DISPLAY INVISIBLE (-5848 5100);
FORCEADD TAP..1
R 2
(-5850 5000);
FORCEPROP 3 LASTPIN (-5800 5000) SIG_NAME M_I_CPU1_SA_DQS_DN<9>
J 0
(-5790 5010);
DISPLAY 0.659574 (-5790 5010);
PAINT MONO (-5790 5010);
DISPLAY INVISIBLE (-5790 5010);
FORCEPROP 1 LASTPIN (-5800 5000) BN 9
J 2
(-5788 5008);
DISPLAY 0.489362 (-5788 5008);
PAINT GREEN (-5788 5008);
FORCEPROP 2 LAST CDS_LIB mstr_standard
J 2
(-5850 5000);
DISPLAY 0.723404 (-5850 5000);
PAINT MONO (-5850 5000);
DISPLAY INVISIBLE (-5850 5000);
FORCEPROP 1 LAST BODY_TYPE PLUMBING
J 2
(-5850 5050);
DISPLAY 0.872340 (-5850 5050);
PAINT GREEN (-5850 5050);
DISPLAY INVISIBLE (-5850 5050);
FORCEPROP 1 LAST HDL_TAP TRUE
J 2
(-6175 4875);
DISPLAY 0.872340 (-6175 4875);
DISPLAY INVISIBLE (-6175 4875);
FORCEPROP 1 LAST PATH I272
J 2
(-5848 5000);
DISPLAY 0.872340 (-5848 5000);
PAINT GREEN (-5848 5000);
DISPLAY INVISIBLE (-5848 5000);
FORCEADD TAP..1
R 2
(-5850 4850);
FORCEPROP 3 LASTPIN (-5800 4850) SIG_NAME M_I_CPU1_SB_DQS_DN<0>
J 0
(-5790 4860);
DISPLAY 0.659574 (-5790 4860);
PAINT MONO (-5790 4860);
DISPLAY INVISIBLE (-5790 4860);
FORCEPROP 1 LASTPIN (-5800 4850) BN 0
J 2
(-5788 4858);
DISPLAY 0.489362 (-5788 4858);
PAINT GREEN (-5788 4858);
FORCEPROP 2 LAST CDS_LIB mstr_standard
J 2
(-5850 4850);
DISPLAY 0.723404 (-5850 4850);
PAINT MONO (-5850 4850);
DISPLAY INVISIBLE (-5850 4850);
FORCEPROP 1 LAST BODY_TYPE PLUMBING
J 2
(-5850 4900);
DISPLAY 0.872340 (-5850 4900);
PAINT GREEN (-5850 4900);
DISPLAY INVISIBLE (-5850 4900);
FORCEPROP 1 LAST HDL_TAP TRUE
J 2
(-6175 4725);
DISPLAY 0.872340 (-6175 4725);
DISPLAY INVISIBLE (-6175 4725);
FORCEPROP 1 LAST PATH I273
J 2
(-5848 4850);
DISPLAY 0.872340 (-5848 4850);
PAINT GREEN (-5848 4850);
DISPLAY INVISIBLE (-5848 4850);
FORCEADD TAP..1
R 2
(-5850 4650);
FORCEPROP 3 LASTPIN (-5800 4650) SIG_NAME M_I_CPU1_SB_DQS_DN<2>
J 0
(-5790 4660);
DISPLAY 0.659574 (-5790 4660);
PAINT MONO (-5790 4660);
DISPLAY INVISIBLE (-5790 4660);
FORCEPROP 1 LASTPIN (-5800 4650) BN 2
J 2
(-5788 4658);
DISPLAY 0.489362 (-5788 4658);
PAINT GREEN (-5788 4658);
FORCEPROP 2 LAST CDS_LIB mstr_standard
J 2
(-5850 4650);
DISPLAY 0.723404 (-5850 4650);
PAINT MONO (-5850 4650);
DISPLAY INVISIBLE (-5850 4650);
FORCEPROP 1 LAST BODY_TYPE PLUMBING
J 2
(-5850 4700);
DISPLAY 0.872340 (-5850 4700);
PAINT GREEN (-5850 4700);
DISPLAY INVISIBLE (-5850 4700);
FORCEPROP 1 LAST HDL_TAP TRUE
J 2
(-6175 4525);
DISPLAY 0.872340 (-6175 4525);
DISPLAY INVISIBLE (-6175 4525);
FORCEPROP 1 LAST PATH I274
J 2
(-5848 4650);
DISPLAY 0.872340 (-5848 4650);
PAINT GREEN (-5848 4650);
DISPLAY INVISIBLE (-5848 4650);
FORCEADD TAP..1
R 2
(-5850 4750);
FORCEPROP 3 LASTPIN (-5800 4750) SIG_NAME M_I_CPU1_SB_DQS_DN<1>
J 0
(-5790 4760);
DISPLAY 0.659574 (-5790 4760);
PAINT MONO (-5790 4760);
DISPLAY INVISIBLE (-5790 4760);
FORCEPROP 1 LASTPIN (-5800 4750) BN 1
J 2
(-5788 4758);
DISPLAY 0.489362 (-5788 4758);
PAINT GREEN (-5788 4758);
FORCEPROP 2 LAST CDS_LIB mstr_standard
J 2
(-5850 4750);
DISPLAY 0.723404 (-5850 4750);
PAINT MONO (-5850 4750);
DISPLAY INVISIBLE (-5850 4750);
FORCEPROP 1 LAST BODY_TYPE PLUMBING
J 2
(-5850 4800);
DISPLAY 0.872340 (-5850 4800);
PAINT GREEN (-5850 4800);
DISPLAY INVISIBLE (-5850 4800);
FORCEPROP 1 LAST HDL_TAP TRUE
J 2
(-6175 4625);
DISPLAY 0.872340 (-6175 4625);
DISPLAY INVISIBLE (-6175 4625);
FORCEPROP 1 LAST PATH I275
J 2
(-5848 4750);
DISPLAY 0.872340 (-5848 4750);
PAINT GREEN (-5848 4750);
DISPLAY INVISIBLE (-5848 4750);
FORCEADD TAP..1
R 2
(-5850 4450);
FORCEPROP 3 LASTPIN (-5800 4450) SIG_NAME M_I_CPU1_SB_DQS_DN<4>
J 0
(-5790 4460);
DISPLAY 0.659574 (-5790 4460);
PAINT MONO (-5790 4460);
DISPLAY INVISIBLE (-5790 4460);
FORCEPROP 1 LASTPIN (-5800 4450) BN 4
J 2
(-5788 4458);
DISPLAY 0.489362 (-5788 4458);
PAINT GREEN (-5788 4458);
FORCEPROP 2 LAST CDS_LIB mstr_standard
J 2
(-5850 4450);
DISPLAY 0.723404 (-5850 4450);
PAINT MONO (-5850 4450);
DISPLAY INVISIBLE (-5850 4450);
FORCEPROP 1 LAST BODY_TYPE PLUMBING
J 2
(-5850 4500);
DISPLAY 0.872340 (-5850 4500);
PAINT GREEN (-5850 4500);
DISPLAY INVISIBLE (-5850 4500);
FORCEPROP 1 LAST HDL_TAP TRUE
J 2
(-6175 4325);
DISPLAY 0.872340 (-6175 4325);
DISPLAY INVISIBLE (-6175 4325);
FORCEPROP 1 LAST PATH I276
J 2
(-5848 4450);
DISPLAY 0.872340 (-5848 4450);
PAINT GREEN (-5848 4450);
DISPLAY INVISIBLE (-5848 4450);
FORCEADD TAP..1
R 2
(-5850 4550);
FORCEPROP 3 LASTPIN (-5800 4550) SIG_NAME M_I_CPU1_SB_DQS_DN<3>
J 0
(-5790 4560);
DISPLAY 0.659574 (-5790 4560);
PAINT MONO (-5790 4560);
DISPLAY INVISIBLE (-5790 4560);
FORCEPROP 1 LASTPIN (-5800 4550) BN 3
J 2
(-5788 4558);
DISPLAY 0.489362 (-5788 4558);
PAINT GREEN (-5788 4558);
FORCEPROP 2 LAST CDS_LIB mstr_standard
J 2
(-5850 4550);
DISPLAY 0.723404 (-5850 4550);
PAINT MONO (-5850 4550);
DISPLAY INVISIBLE (-5850 4550);
FORCEPROP 1 LAST BODY_TYPE PLUMBING
J 2
(-5850 4600);
DISPLAY 0.872340 (-5850 4600);
PAINT GREEN (-5850 4600);
DISPLAY INVISIBLE (-5850 4600);
FORCEPROP 1 LAST HDL_TAP TRUE
J 2
(-6175 4425);
DISPLAY 0.872340 (-6175 4425);
DISPLAY INVISIBLE (-6175 4425);
FORCEPROP 1 LAST PATH I277
J 2
(-5848 4550);
DISPLAY 0.872340 (-5848 4550);
PAINT GREEN (-5848 4550);
DISPLAY INVISIBLE (-5848 4550);
FORCEADD TAP..1
R 2
(-5850 4350);
FORCEPROP 3 LASTPIN (-5800 4350) SIG_NAME M_I_CPU1_SB_DQS_DN<5>
J 0
(-5790 4360);
DISPLAY 0.659574 (-5790 4360);
PAINT MONO (-5790 4360);
DISPLAY INVISIBLE (-5790 4360);
FORCEPROP 1 LASTPIN (-5800 4350) BN 5
J 2
(-5788 4358);
DISPLAY 0.489362 (-5788 4358);
PAINT GREEN (-5788 4358);
FORCEPROP 2 LAST CDS_LIB mstr_standard
J 2
(-5850 4350);
DISPLAY 0.723404 (-5850 4350);
PAINT MONO (-5850 4350);
DISPLAY INVISIBLE (-5850 4350);
FORCEPROP 1 LAST BODY_TYPE PLUMBING
J 2
(-5850 4400);
DISPLAY 0.872340 (-5850 4400);
PAINT GREEN (-5850 4400);
DISPLAY INVISIBLE (-5850 4400);
FORCEPROP 1 LAST HDL_TAP TRUE
J 2
(-6175 4225);
DISPLAY 0.872340 (-6175 4225);
DISPLAY INVISIBLE (-6175 4225);
FORCEPROP 1 LAST PATH I278
J 2
(-5848 4350);
DISPLAY 0.872340 (-5848 4350);
PAINT GREEN (-5848 4350);
DISPLAY INVISIBLE (-5848 4350);
FORCEADD TAP..1
R 2
(-5850 4250);
FORCEPROP 3 LASTPIN (-5800 4250) SIG_NAME M_I_CPU1_SB_DQS_DN<6>
J 0
(-5790 4260);
DISPLAY 0.659574 (-5790 4260);
PAINT MONO (-5790 4260);
DISPLAY INVISIBLE (-5790 4260);
FORCEPROP 1 LASTPIN (-5800 4250) BN 6
J 2
(-5788 4258);
DISPLAY 0.489362 (-5788 4258);
PAINT GREEN (-5788 4258);
FORCEPROP 2 LAST CDS_LIB mstr_standard
J 2
(-5850 4250);
DISPLAY 0.723404 (-5850 4250);
PAINT MONO (-5850 4250);
DISPLAY INVISIBLE (-5850 4250);
FORCEPROP 1 LAST BODY_TYPE PLUMBING
J 2
(-5850 4300);
DISPLAY 0.872340 (-5850 4300);
PAINT GREEN (-5850 4300);
DISPLAY INVISIBLE (-5850 4300);
FORCEPROP 1 LAST HDL_TAP TRUE
J 2
(-6175 4125);
DISPLAY 0.872340 (-6175 4125);
DISPLAY INVISIBLE (-6175 4125);
FORCEPROP 1 LAST PATH I279
J 2
(-5848 4250);
DISPLAY 0.872340 (-5848 4250);
PAINT GREEN (-5848 4250);
DISPLAY INVISIBLE (-5848 4250);
FORCEADD TAP..1
R 2
(-5850 4150);
FORCEPROP 3 LASTPIN (-5800 4150) SIG_NAME M_I_CPU1_SB_DQS_DN<7>
J 0
(-5790 4160);
DISPLAY 0.659574 (-5790 4160);
PAINT MONO (-5790 4160);
DISPLAY INVISIBLE (-5790 4160);
FORCEPROP 1 LASTPIN (-5800 4150) BN 7
J 2
(-5788 4158);
DISPLAY 0.489362 (-5788 4158);
PAINT GREEN (-5788 4158);
FORCEPROP 2 LAST CDS_LIB mstr_standard
J 2
(-5850 4150);
DISPLAY 0.723404 (-5850 4150);
PAINT MONO (-5850 4150);
DISPLAY INVISIBLE (-5850 4150);
FORCEPROP 1 LAST BODY_TYPE PLUMBING
J 2
(-5850 4200);
DISPLAY 0.872340 (-5850 4200);
PAINT GREEN (-5850 4200);
DISPLAY INVISIBLE (-5850 4200);
FORCEPROP 1 LAST HDL_TAP TRUE
J 2
(-6175 4025);
DISPLAY 0.872340 (-6175 4025);
DISPLAY INVISIBLE (-6175 4025);
FORCEPROP 1 LAST PATH I280
J 2
(-5848 4150);
DISPLAY 0.872340 (-5848 4150);
PAINT GREEN (-5848 4150);
DISPLAY INVISIBLE (-5848 4150);
FORCEADD OFFPAGE..3
R 2
(-6550 5975);
FORCEPROP 2 LAST $XR0 106 
J 0
(-6830 5975);
DISPLAY 0.638298 (-6830 5975);
PAINT MONO (-6830 5975);
FORCEPROP 2 LAST CDS_LIB standard
J 0
(-6550 5975);
DISPLAY INVISIBLE (-6550 5975);
FORCEPROP 1 LAST OFFPAGE TRUE
J 2
(-6875 5850);
DISPLAY 0.872340 (-6875 5850);
PAINT GREEN (-6875 5850);
DISPLAY INVISIBLE (-6875 5850);
FORCEPROP 1 LAST COMMENT_BODY TRUE
J 2
(-6500 5875);
DISPLAY 0.872340 (-6500 5875);
PAINT GREEN (-6500 5875);
DISPLAY INVISIBLE (-6500 5875);
FORCEPROP 2 LAST PATH I281
J 0
(-6825 6025);
DISPLAY 1.021277 (-6825 6025);
DISPLAY INVISIBLE (-6825 6025);
FORCEADD OFFPAGE..3
R 2
(-6550 5925);
FORCEPROP 2 LAST $XR0 106 
J 0
(-6830 5925);
DISPLAY 0.638298 (-6830 5925);
PAINT MONO (-6830 5925);
FORCEPROP 2 LAST CDS_LIB standard
J 0
(-6550 5925);
DISPLAY INVISIBLE (-6550 5925);
FORCEPROP 1 LAST OFFPAGE TRUE
J 2
(-6875 5800);
DISPLAY 0.872340 (-6875 5800);
PAINT GREEN (-6875 5800);
DISPLAY INVISIBLE (-6875 5800);
FORCEPROP 1 LAST COMMENT_BODY TRUE
J 2
(-6500 5825);
DISPLAY 0.872340 (-6500 5825);
PAINT GREEN (-6500 5825);
DISPLAY INVISIBLE (-6500 5825);
FORCEPROP 2 LAST PATH I282
J 0
(-6825 5975);
DISPLAY 1.021277 (-6825 5975);
DISPLAY INVISIBLE (-6825 5975);
FORCEADD OFFPAGE..3
R 2
(-6550 4925);
FORCEPROP 2 LAST $XR0 106 
J 0
(-6830 4925);
DISPLAY 0.638298 (-6830 4925);
PAINT MONO (-6830 4925);
FORCEPROP 2 LAST CDS_LIB standard
J 0
(-6550 4925);
DISPLAY INVISIBLE (-6550 4925);
FORCEPROP 1 LAST OFFPAGE TRUE
J 2
(-6875 4800);
DISPLAY 0.872340 (-6875 4800);
PAINT GREEN (-6875 4800);
DISPLAY INVISIBLE (-6875 4800);
FORCEPROP 1 LAST COMMENT_BODY TRUE
J 2
(-6500 4825);
DISPLAY 0.872340 (-6500 4825);
PAINT GREEN (-6500 4825);
DISPLAY INVISIBLE (-6500 4825);
FORCEPROP 2 LAST PATH I283
J 0
(-6825 4975);
DISPLAY 1.021277 (-6825 4975);
DISPLAY INVISIBLE (-6825 4975);
FORCEADD OFFPAGE..3
R 2
(-6550 4875);
FORCEPROP 2 LAST $XR0 106 
J 0
(-6830 4875);
DISPLAY 0.638298 (-6830 4875);
PAINT MONO (-6830 4875);
FORCEPROP 2 LAST CDS_LIB standard
J 0
(-6550 4875);
DISPLAY INVISIBLE (-6550 4875);
FORCEPROP 1 LAST OFFPAGE TRUE
J 2
(-6875 4750);
DISPLAY 0.872340 (-6875 4750);
PAINT GREEN (-6875 4750);
DISPLAY INVISIBLE (-6875 4750);
FORCEPROP 1 LAST COMMENT_BODY TRUE
J 2
(-6500 4775);
DISPLAY 0.872340 (-6500 4775);
PAINT GREEN (-6500 4775);
DISPLAY INVISIBLE (-6500 4775);
FORCEPROP 2 LAST PATH I284
J 0
(-6825 4925);
DISPLAY 1.021277 (-6825 4925);
DISPLAY INVISIBLE (-6825 4925);
FORCEADD TAP..1
R 2
(-5650 4000);
FORCEPROP 3 LASTPIN (-5600 4000) SIG_NAME M_I_CPU1_SB_DQS_DP<9>
J 0
(-5590 4010);
DISPLAY 0.659574 (-5590 4010);
PAINT MONO (-5590 4010);
DISPLAY INVISIBLE (-5590 4010);
FORCEPROP 1 LASTPIN (-5600 4000) BN 9
J 2
(-5588 4008);
DISPLAY 0.489362 (-5588 4008);
PAINT GREEN (-5588 4008);
FORCEPROP 2 LAST CDS_LIB mstr_standard
J 2
(-5650 4000);
DISPLAY 0.723404 (-5650 4000);
PAINT MONO (-5650 4000);
DISPLAY INVISIBLE (-5650 4000);
FORCEPROP 1 LAST BODY_TYPE PLUMBING
J 2
(-5650 4050);
DISPLAY 0.872340 (-5650 4050);
PAINT GREEN (-5650 4050);
DISPLAY INVISIBLE (-5650 4050);
FORCEPROP 1 LAST HDL_TAP TRUE
J 2
(-5975 3875);
DISPLAY 0.872340 (-5975 3875);
DISPLAY INVISIBLE (-5975 3875);
FORCEPROP 1 LAST PATH I285
J 2
(-5648 4000);
DISPLAY 0.872340 (-5648 4000);
PAINT GREEN (-5648 4000);
DISPLAY INVISIBLE (-5648 4000);
FORCEADD TAP..1
R 2
(-5850 3950);
FORCEPROP 3 LASTPIN (-5800 3950) SIG_NAME M_I_CPU1_SB_DQS_DN<9>
J 0
(-5790 3960);
DISPLAY 0.659574 (-5790 3960);
PAINT MONO (-5790 3960);
DISPLAY INVISIBLE (-5790 3960);
FORCEPROP 1 LASTPIN (-5800 3950) BN 9
J 2
(-5788 3958);
DISPLAY 0.489362 (-5788 3958);
PAINT GREEN (-5788 3958);
FORCEPROP 2 LAST CDS_LIB mstr_standard
J 2
(-5850 3950);
DISPLAY 0.723404 (-5850 3950);
PAINT MONO (-5850 3950);
DISPLAY INVISIBLE (-5850 3950);
FORCEPROP 1 LAST BODY_TYPE PLUMBING
J 2
(-5850 4000);
DISPLAY 0.872340 (-5850 4000);
PAINT GREEN (-5850 4000);
DISPLAY INVISIBLE (-5850 4000);
FORCEPROP 1 LAST HDL_TAP TRUE
J 2
(-6175 3825);
DISPLAY 0.872340 (-6175 3825);
DISPLAY INVISIBLE (-6175 3825);
FORCEPROP 1 LAST PATH I286
J 2
(-5848 3950);
DISPLAY 0.872340 (-5848 3950);
PAINT GREEN (-5848 3950);
DISPLAY INVISIBLE (-5848 3950);
FORCEADD TAP..1
R 2
(-5850 4050);
FORCEPROP 3 LASTPIN (-5800 4050) SIG_NAME M_I_CPU1_SB_DQS_DN<8>
J 0
(-5790 4060);
DISPLAY 0.659574 (-5790 4060);
PAINT MONO (-5790 4060);
DISPLAY INVISIBLE (-5790 4060);
FORCEPROP 1 LASTPIN (-5800 4050) BN 8
J 2
(-5788 4058);
DISPLAY 0.489362 (-5788 4058);
PAINT GREEN (-5788 4058);
FORCEPROP 2 LAST CDS_LIB mstr_standard
J 2
(-5850 4050);
DISPLAY 0.723404 (-5850 4050);
PAINT MONO (-5850 4050);
DISPLAY INVISIBLE (-5850 4050);
FORCEPROP 1 LAST BODY_TYPE PLUMBING
J 2
(-5850 4100);
DISPLAY 0.872340 (-5850 4100);
PAINT GREEN (-5850 4100);
DISPLAY INVISIBLE (-5850 4100);
FORCEPROP 1 LAST HDL_TAP TRUE
J 2
(-6175 3925);
DISPLAY 0.872340 (-6175 3925);
DISPLAY INVISIBLE (-6175 3925);
FORCEPROP 1 LAST PATH I287
J 2
(-5848 4050);
DISPLAY 0.872340 (-5848 4050);
PAINT GREEN (-5848 4050);
DISPLAY INVISIBLE (-5848 4050);
FORCEADD TAP..1
R 2
(-5850 3750);
FORCEPROP 3 LASTPIN (-5800 3750) SIG_NAME M_I_CPU1_SA_CA<1>
J 0
(-5790 3760);
DISPLAY 0.659574 (-5790 3760);
PAINT MONO (-5790 3760);
DISPLAY INVISIBLE (-5790 3760);
FORCEPROP 1 LASTPIN (-5800 3750) BN 1
J 2
(-5788 3758);
DISPLAY 0.489362 (-5788 3758);
PAINT GREEN (-5788 3758);
FORCEPROP 2 LAST CDS_LIB mstr_standard
J 0
(-5850 3750);
DISPLAY 0.723404 (-5850 3750);
PAINT MONO (-5850 3750);
DISPLAY INVISIBLE (-5850 3750);
FORCEPROP 1 LAST BODY_TYPE PLUMBING
J 2
(-5850 3800);
DISPLAY 0.872340 (-5850 3800);
PAINT GREEN (-5850 3800);
DISPLAY INVISIBLE (-5850 3800);
FORCEPROP 1 LAST HDL_TAP TRUE
J 2
(-6175 3625);
DISPLAY 0.872340 (-6175 3625);
DISPLAY INVISIBLE (-6175 3625);
FORCEPROP 1 LAST PATH I288
J 2
(-5848 3750);
DISPLAY 0.872340 (-5848 3750);
PAINT GREEN (-5848 3750);
DISPLAY INVISIBLE (-5848 3750);
FORCEADD TAP..1
R 2
(-5850 3800);
FORCEPROP 3 LASTPIN (-5800 3800) SIG_NAME M_I_CPU1_SA_CA<0>
J 0
(-5790 3810);
DISPLAY 0.659574 (-5790 3810);
PAINT MONO (-5790 3810);
DISPLAY INVISIBLE (-5790 3810);
FORCEPROP 1 LASTPIN (-5800 3800) BN 0
J 2
(-5788 3808);
DISPLAY 0.489362 (-5788 3808);
PAINT GREEN (-5788 3808);
FORCEPROP 2 LAST CDS_LIB mstr_standard
J 0
(-5850 3800);
DISPLAY 0.723404 (-5850 3800);
PAINT MONO (-5850 3800);
DISPLAY INVISIBLE (-5850 3800);
FORCEPROP 1 LAST BODY_TYPE PLUMBING
J 2
(-5850 3850);
DISPLAY 0.872340 (-5850 3850);
PAINT GREEN (-5850 3850);
DISPLAY INVISIBLE (-5850 3850);
FORCEPROP 1 LAST HDL_TAP TRUE
J 2
(-6175 3675);
DISPLAY 0.872340 (-6175 3675);
DISPLAY INVISIBLE (-6175 3675);
FORCEPROP 1 LAST PATH I289
J 2
(-5848 3800);
DISPLAY 0.872340 (-5848 3800);
PAINT GREEN (-5848 3800);
DISPLAY INVISIBLE (-5848 3800);
FORCEADD TAP..1
R 2
(-5850 3700);
FORCEPROP 3 LASTPIN (-5800 3700) SIG_NAME M_I_CPU1_SA_CA<2>
J 0
(-5790 3710);
DISPLAY 0.659574 (-5790 3710);
PAINT MONO (-5790 3710);
DISPLAY INVISIBLE (-5790 3710);
FORCEPROP 1 LASTPIN (-5800 3700) BN 2
J 2
(-5788 3708);
DISPLAY 0.489362 (-5788 3708);
PAINT GREEN (-5788 3708);
FORCEPROP 2 LAST CDS_LIB mstr_standard
J 0
(-5850 3700);
DISPLAY 0.723404 (-5850 3700);
PAINT MONO (-5850 3700);
DISPLAY INVISIBLE (-5850 3700);
FORCEPROP 1 LAST BODY_TYPE PLUMBING
J 2
(-5850 3750);
DISPLAY 0.872340 (-5850 3750);
PAINT GREEN (-5850 3750);
DISPLAY INVISIBLE (-5850 3750);
FORCEPROP 1 LAST HDL_TAP TRUE
J 2
(-6175 3575);
DISPLAY 0.872340 (-6175 3575);
DISPLAY INVISIBLE (-6175 3575);
FORCEPROP 1 LAST PATH I290
J 2
(-5848 3700);
DISPLAY 0.872340 (-5848 3700);
PAINT GREEN (-5848 3700);
DISPLAY INVISIBLE (-5848 3700);
FORCEADD TAP..1
R 2
(-5850 3650);
FORCEPROP 3 LASTPIN (-5800 3650) SIG_NAME M_I_CPU1_SA_CA<3>
J 0
(-5790 3660);
DISPLAY 0.659574 (-5790 3660);
PAINT MONO (-5790 3660);
DISPLAY INVISIBLE (-5790 3660);
FORCEPROP 1 LASTPIN (-5800 3650) BN 3
J 2
(-5788 3658);
DISPLAY 0.489362 (-5788 3658);
PAINT GREEN (-5788 3658);
FORCEPROP 2 LAST CDS_LIB mstr_standard
J 0
(-5850 3650);
DISPLAY 0.723404 (-5850 3650);
PAINT MONO (-5850 3650);
DISPLAY INVISIBLE (-5850 3650);
FORCEPROP 1 LAST BODY_TYPE PLUMBING
J 2
(-5850 3700);
DISPLAY 0.872340 (-5850 3700);
PAINT GREEN (-5850 3700);
DISPLAY INVISIBLE (-5850 3700);
FORCEPROP 1 LAST HDL_TAP TRUE
J 2
(-6175 3525);
DISPLAY 0.872340 (-6175 3525);
DISPLAY INVISIBLE (-6175 3525);
FORCEPROP 1 LAST PATH I291
J 2
(-5848 3650);
DISPLAY 0.872340 (-5848 3650);
PAINT GREEN (-5848 3650);
DISPLAY INVISIBLE (-5848 3650);
FORCEADD TAP..1
R 2
(-5850 3600);
FORCEPROP 3 LASTPIN (-5800 3600) SIG_NAME M_I_CPU1_SA_CA<4>
J 0
(-5790 3610);
DISPLAY 0.659574 (-5790 3610);
PAINT MONO (-5790 3610);
DISPLAY INVISIBLE (-5790 3610);
FORCEPROP 1 LASTPIN (-5800 3600) BN 4
J 2
(-5788 3608);
DISPLAY 0.489362 (-5788 3608);
PAINT GREEN (-5788 3608);
FORCEPROP 2 LAST CDS_LIB mstr_standard
J 0
(-5850 3600);
DISPLAY 0.723404 (-5850 3600);
PAINT MONO (-5850 3600);
DISPLAY INVISIBLE (-5850 3600);
FORCEPROP 1 LAST BODY_TYPE PLUMBING
J 2
(-5850 3650);
DISPLAY 0.872340 (-5850 3650);
PAINT GREEN (-5850 3650);
DISPLAY INVISIBLE (-5850 3650);
FORCEPROP 1 LAST HDL_TAP TRUE
J 2
(-6175 3475);
DISPLAY 0.872340 (-6175 3475);
DISPLAY INVISIBLE (-6175 3475);
FORCEPROP 1 LAST PATH I292
J 2
(-5848 3600);
DISPLAY 0.872340 (-5848 3600);
PAINT GREEN (-5848 3600);
DISPLAY INVISIBLE (-5848 3600);
FORCEADD TAP..1
R 2
(-5850 3400);
FORCEPROP 3 LASTPIN (-5800 3400) SIG_NAME M_I_CPU1_SB_CA<0>
J 0
(-5790 3410);
DISPLAY 0.659574 (-5790 3410);
PAINT MONO (-5790 3410);
DISPLAY INVISIBLE (-5790 3410);
FORCEPROP 1 LASTPIN (-5800 3400) BN 0
J 2
(-5788 3408);
DISPLAY 0.489362 (-5788 3408);
PAINT GREEN (-5788 3408);
FORCEPROP 2 LAST CDS_LIB mstr_standard
J 0
(-5850 3400);
DISPLAY 0.723404 (-5850 3400);
PAINT MONO (-5850 3400);
DISPLAY INVISIBLE (-5850 3400);
FORCEPROP 1 LAST BODY_TYPE PLUMBING
J 2
(-5850 3450);
DISPLAY 0.872340 (-5850 3450);
PAINT GREEN (-5850 3450);
DISPLAY INVISIBLE (-5850 3450);
FORCEPROP 1 LAST HDL_TAP TRUE
J 2
(-6175 3275);
DISPLAY 0.872340 (-6175 3275);
DISPLAY INVISIBLE (-6175 3275);
FORCEPROP 1 LAST PATH I293
J 2
(-5848 3400);
DISPLAY 0.872340 (-5848 3400);
PAINT GREEN (-5848 3400);
DISPLAY INVISIBLE (-5848 3400);
FORCEADD TAP..1
R 2
(-5850 3350);
FORCEPROP 3 LASTPIN (-5800 3350) SIG_NAME M_I_CPU1_SB_CA<1>
J 0
(-5790 3360);
DISPLAY 0.659574 (-5790 3360);
PAINT MONO (-5790 3360);
DISPLAY INVISIBLE (-5790 3360);
FORCEPROP 1 LASTPIN (-5800 3350) BN 1
J 2
(-5788 3358);
DISPLAY 0.489362 (-5788 3358);
PAINT GREEN (-5788 3358);
FORCEPROP 2 LAST CDS_LIB mstr_standard
J 0
(-5850 3350);
DISPLAY 0.723404 (-5850 3350);
PAINT MONO (-5850 3350);
DISPLAY INVISIBLE (-5850 3350);
FORCEPROP 1 LAST BODY_TYPE PLUMBING
J 2
(-5850 3400);
DISPLAY 0.872340 (-5850 3400);
PAINT GREEN (-5850 3400);
DISPLAY INVISIBLE (-5850 3400);
FORCEPROP 1 LAST HDL_TAP TRUE
J 2
(-6175 3225);
DISPLAY 0.872340 (-6175 3225);
DISPLAY INVISIBLE (-6175 3225);
FORCEPROP 1 LAST PATH I294
J 2
(-5848 3350);
DISPLAY 0.872340 (-5848 3350);
PAINT GREEN (-5848 3350);
DISPLAY INVISIBLE (-5848 3350);
FORCEADD TAP..1
R 2
(-5850 3550);
FORCEPROP 3 LASTPIN (-5800 3550) SIG_NAME M_I_CPU1_SA_CA<5>
J 0
(-5790 3560);
DISPLAY 0.659574 (-5790 3560);
PAINT MONO (-5790 3560);
DISPLAY INVISIBLE (-5790 3560);
FORCEPROP 1 LASTPIN (-5800 3550) BN 5
J 2
(-5788 3558);
DISPLAY 0.489362 (-5788 3558);
PAINT GREEN (-5788 3558);
FORCEPROP 2 LAST CDS_LIB mstr_standard
J 0
(-5850 3550);
DISPLAY 0.723404 (-5850 3550);
PAINT MONO (-5850 3550);
DISPLAY INVISIBLE (-5850 3550);
FORCEPROP 1 LAST BODY_TYPE PLUMBING
J 2
(-5850 3600);
DISPLAY 0.872340 (-5850 3600);
PAINT GREEN (-5850 3600);
DISPLAY INVISIBLE (-5850 3600);
FORCEPROP 1 LAST HDL_TAP TRUE
J 2
(-6175 3425);
DISPLAY 0.872340 (-6175 3425);
DISPLAY INVISIBLE (-6175 3425);
FORCEPROP 1 LAST PATH I295
J 2
(-5848 3550);
DISPLAY 0.872340 (-5848 3550);
PAINT GREEN (-5848 3550);
DISPLAY INVISIBLE (-5848 3550);
FORCEADD TAP..1
R 2
(-5850 3500);
FORCEPROP 3 LASTPIN (-5800 3500) SIG_NAME M_I_CPU1_SA_CA<6>
J 0
(-5790 3510);
DISPLAY 0.659574 (-5790 3510);
PAINT MONO (-5790 3510);
DISPLAY INVISIBLE (-5790 3510);
FORCEPROP 1 LASTPIN (-5800 3500) BN 6
J 2
(-5788 3508);
DISPLAY 0.489362 (-5788 3508);
PAINT GREEN (-5788 3508);
FORCEPROP 2 LAST CDS_LIB mstr_standard
J 0
(-5850 3500);
DISPLAY 0.723404 (-5850 3500);
PAINT MONO (-5850 3500);
DISPLAY INVISIBLE (-5850 3500);
FORCEPROP 1 LAST BODY_TYPE PLUMBING
J 2
(-5850 3550);
DISPLAY 0.872340 (-5850 3550);
PAINT GREEN (-5850 3550);
DISPLAY INVISIBLE (-5850 3550);
FORCEPROP 1 LAST HDL_TAP TRUE
J 2
(-6175 3375);
DISPLAY 0.872340 (-6175 3375);
DISPLAY INVISIBLE (-6175 3375);
FORCEPROP 1 LAST PATH I296
J 2
(-5848 3500);
DISPLAY 0.872340 (-5848 3500);
PAINT GREEN (-5848 3500);
DISPLAY INVISIBLE (-5848 3500);
FORCEADD TAP..1
R 2
(-5850 3300);
FORCEPROP 3 LASTPIN (-5800 3300) SIG_NAME M_I_CPU1_SB_CA<2>
J 0
(-5790 3310);
DISPLAY 0.659574 (-5790 3310);
PAINT MONO (-5790 3310);
DISPLAY INVISIBLE (-5790 3310);
FORCEPROP 1 LASTPIN (-5800 3300) BN 2
J 2
(-5788 3308);
DISPLAY 0.489362 (-5788 3308);
PAINT GREEN (-5788 3308);
FORCEPROP 2 LAST CDS_LIB mstr_standard
J 0
(-5850 3300);
DISPLAY 0.723404 (-5850 3300);
PAINT MONO (-5850 3300);
DISPLAY INVISIBLE (-5850 3300);
FORCEPROP 1 LAST BODY_TYPE PLUMBING
J 2
(-5850 3350);
DISPLAY 0.872340 (-5850 3350);
PAINT GREEN (-5850 3350);
DISPLAY INVISIBLE (-5850 3350);
FORCEPROP 1 LAST HDL_TAP TRUE
J 2
(-6175 3175);
DISPLAY 0.872340 (-6175 3175);
DISPLAY INVISIBLE (-6175 3175);
FORCEPROP 1 LAST PATH I297
J 2
(-5848 3300);
DISPLAY 0.872340 (-5848 3300);
PAINT GREEN (-5848 3300);
DISPLAY INVISIBLE (-5848 3300);
FORCEADD TAP..1
R 2
(-5850 3250);
FORCEPROP 3 LASTPIN (-5800 3250) SIG_NAME M_I_CPU1_SB_CA<3>
J 0
(-5790 3260);
DISPLAY 0.659574 (-5790 3260);
PAINT MONO (-5790 3260);
DISPLAY INVISIBLE (-5790 3260);
FORCEPROP 1 LASTPIN (-5800 3250) BN 3
J 2
(-5788 3258);
DISPLAY 0.489362 (-5788 3258);
PAINT GREEN (-5788 3258);
FORCEPROP 2 LAST CDS_LIB mstr_standard
J 0
(-5850 3250);
DISPLAY 0.723404 (-5850 3250);
PAINT MONO (-5850 3250);
DISPLAY INVISIBLE (-5850 3250);
FORCEPROP 1 LAST BODY_TYPE PLUMBING
J 2
(-5850 3300);
DISPLAY 0.872340 (-5850 3300);
PAINT GREEN (-5850 3300);
DISPLAY INVISIBLE (-5850 3300);
FORCEPROP 1 LAST HDL_TAP TRUE
J 2
(-6175 3125);
DISPLAY 0.872340 (-6175 3125);
DISPLAY INVISIBLE (-6175 3125);
FORCEPROP 1 LAST PATH I298
J 2
(-5848 3250);
DISPLAY 0.872340 (-5848 3250);
PAINT GREEN (-5848 3250);
DISPLAY INVISIBLE (-5848 3250);
FORCEADD TAP..1
R 2
(-5850 3200);
FORCEPROP 3 LASTPIN (-5800 3200) SIG_NAME M_I_CPU1_SB_CA<4>
J 0
(-5790 3210);
DISPLAY 0.659574 (-5790 3210);
PAINT MONO (-5790 3210);
DISPLAY INVISIBLE (-5790 3210);
FORCEPROP 1 LASTPIN (-5800 3200) BN 4
J 2
(-5788 3208);
DISPLAY 0.489362 (-5788 3208);
PAINT GREEN (-5788 3208);
FORCEPROP 2 LAST CDS_LIB mstr_standard
J 0
(-5850 3200);
DISPLAY 0.723404 (-5850 3200);
PAINT MONO (-5850 3200);
DISPLAY INVISIBLE (-5850 3200);
FORCEPROP 1 LAST BODY_TYPE PLUMBING
J 2
(-5850 3250);
DISPLAY 0.872340 (-5850 3250);
PAINT GREEN (-5850 3250);
DISPLAY INVISIBLE (-5850 3250);
FORCEPROP 1 LAST HDL_TAP TRUE
J 2
(-6175 3075);
DISPLAY 0.872340 (-6175 3075);
DISPLAY INVISIBLE (-6175 3075);
FORCEPROP 1 LAST PATH I299
J 2
(-5848 3200);
DISPLAY 0.872340 (-5848 3200);
PAINT GREEN (-5848 3200);
DISPLAY INVISIBLE (-5848 3200);
FORCEADD TAP..1
R 2
(-5850 3150);
FORCEPROP 3 LASTPIN (-5800 3150) SIG_NAME M_I_CPU1_SB_CA<5>
J 0
(-5790 3160);
DISPLAY 0.659574 (-5790 3160);
PAINT MONO (-5790 3160);
DISPLAY INVISIBLE (-5790 3160);
FORCEPROP 1 LASTPIN (-5800 3150) BN 5
J 2
(-5788 3158);
DISPLAY 0.489362 (-5788 3158);
PAINT GREEN (-5788 3158);
FORCEPROP 2 LAST CDS_LIB mstr_standard
J 0
(-5850 3150);
DISPLAY 0.723404 (-5850 3150);
PAINT MONO (-5850 3150);
DISPLAY INVISIBLE (-5850 3150);
FORCEPROP 1 LAST BODY_TYPE PLUMBING
J 2
(-5850 3200);
DISPLAY 0.872340 (-5850 3200);
PAINT GREEN (-5850 3200);
DISPLAY INVISIBLE (-5850 3200);
FORCEPROP 1 LAST HDL_TAP TRUE
J 2
(-6175 3025);
DISPLAY 0.872340 (-6175 3025);
DISPLAY INVISIBLE (-6175 3025);
FORCEPROP 1 LAST PATH I300
J 2
(-5848 3150);
DISPLAY 0.872340 (-5848 3150);
PAINT GREEN (-5848 3150);
DISPLAY INVISIBLE (-5848 3150);
FORCEADD TAP..1
R 2
(-5850 3100);
FORCEPROP 3 LASTPIN (-5800 3100) SIG_NAME M_I_CPU1_SB_CA<6>
J 0
(-5790 3110);
DISPLAY 0.659574 (-5790 3110);
PAINT MONO (-5790 3110);
DISPLAY INVISIBLE (-5790 3110);
FORCEPROP 1 LASTPIN (-5800 3100) BN 6
J 2
(-5788 3108);
DISPLAY 0.489362 (-5788 3108);
PAINT GREEN (-5788 3108);
FORCEPROP 2 LAST CDS_LIB mstr_standard
J 0
(-5850 3100);
DISPLAY 0.723404 (-5850 3100);
PAINT MONO (-5850 3100);
DISPLAY INVISIBLE (-5850 3100);
FORCEPROP 1 LAST BODY_TYPE PLUMBING
J 2
(-5850 3150);
DISPLAY 0.872340 (-5850 3150);
PAINT GREEN (-5850 3150);
DISPLAY INVISIBLE (-5850 3150);
FORCEPROP 1 LAST HDL_TAP TRUE
J 2
(-6175 2975);
DISPLAY 0.872340 (-6175 2975);
DISPLAY INVISIBLE (-6175 2975);
FORCEPROP 1 LAST PATH I301
J 2
(-5848 3100);
DISPLAY 0.872340 (-5848 3100);
PAINT GREEN (-5848 3100);
DISPLAY INVISIBLE (-5848 3100);
FORCEADD OFFPAGE..2
R 2
(-6450 3825);
FORCEPROP 2 LAST $XR0 106 
J 0
(-6705 3825);
DISPLAY 0.638298 (-6705 3825);
PAINT MONO (-6705 3825);
FORCEPROP 2 LAST CDS_LIB standard
J 0
(-6450 3825);
DISPLAY INVISIBLE (-6450 3825);
FORCEPROP 1 LAST OFFPAGE TRUE
J 2
(-6775 3700);
DISPLAY 0.872340 (-6775 3700);
PAINT GREEN (-6775 3700);
DISPLAY INVISIBLE (-6775 3700);
FORCEPROP 1 LAST COMMENT_BODY TRUE
J 2
(-6405 3730);
DISPLAY 0.872340 (-6405 3730);
PAINT GREEN (-6405 3730);
DISPLAY INVISIBLE (-6405 3730);
FORCEPROP 2 LAST PATH I302
J 0
(-6700 3875);
DISPLAY 1.021277 (-6700 3875);
DISPLAY INVISIBLE (-6700 3875);
FORCEADD OFFPAGE..2
R 2
(-6450 3425);
FORCEPROP 2 LAST $XR0 106 
J 0
(-6705 3425);
DISPLAY 0.638298 (-6705 3425);
PAINT MONO (-6705 3425);
FORCEPROP 2 LAST CDS_LIB standard
J 0
(-6450 3425);
DISPLAY INVISIBLE (-6450 3425);
FORCEPROP 1 LAST OFFPAGE TRUE
J 2
(-6775 3300);
DISPLAY 0.872340 (-6775 3300);
PAINT GREEN (-6775 3300);
DISPLAY INVISIBLE (-6775 3300);
FORCEPROP 1 LAST COMMENT_BODY TRUE
J 2
(-6405 3330);
DISPLAY 0.872340 (-6405 3330);
PAINT GREEN (-6405 3330);
DISPLAY INVISIBLE (-6405 3330);
FORCEPROP 2 LAST PATH I303
J 0
(-6700 3475);
DISPLAY 1.021277 (-6700 3475);
DISPLAY INVISIBLE (-6700 3475);
FORCEADD OFFPAGE..2
R 2
(-6450 2950);
FORCEPROP 2 LAST $XR0 106 
J 0
(-6705 2950);
DISPLAY 0.638298 (-6705 2950);
PAINT MONO (-6705 2950);
FORCEPROP 2 LAST CDS_LIB standard
J 0
(-6450 2950);
DISPLAY INVISIBLE (-6450 2950);
FORCEPROP 1 LAST OFFPAGE TRUE
J 2
(-6775 2825);
DISPLAY 0.872340 (-6775 2825);
PAINT GREEN (-6775 2825);
DISPLAY INVISIBLE (-6775 2825);
FORCEPROP 1 LAST COMMENT_BODY TRUE
J 2
(-6405 2855);
DISPLAY 0.872340 (-6405 2855);
PAINT GREEN (-6405 2855);
DISPLAY INVISIBLE (-6405 2855);
FORCEPROP 2 LAST PATH I304
J 0
(-6700 3000);
DISPLAY 1.021277 (-6700 3000);
DISPLAY INVISIBLE (-6700 3000);
FORCEADD OFFPAGE..2
R 2
(-6450 2900);
FORCEPROP 2 LAST $XR0 106 
J 0
(-6705 2900);
DISPLAY 0.638298 (-6705 2900);
PAINT MONO (-6705 2900);
FORCEPROP 2 LAST CDS_LIB standard
J 0
(-6450 2900);
DISPLAY INVISIBLE (-6450 2900);
FORCEPROP 1 LAST OFFPAGE TRUE
J 2
(-6775 2775);
DISPLAY 0.872340 (-6775 2775);
PAINT GREEN (-6775 2775);
DISPLAY INVISIBLE (-6775 2775);
FORCEPROP 1 LAST COMMENT_BODY TRUE
J 2
(-6405 2805);
DISPLAY 0.872340 (-6405 2805);
PAINT GREEN (-6405 2805);
DISPLAY INVISIBLE (-6405 2805);
FORCEPROP 2 LAST PATH I305
J 0
(-6700 2950);
DISPLAY 1.021277 (-6700 2950);
DISPLAY INVISIBLE (-6700 2950);
FORCEADD OFFPAGE..2
R 2
(-6450 2750);
FORCEPROP 2 LAST $XR0 106 
J 0
(-6705 2750);
DISPLAY 0.638298 (-6705 2750);
PAINT MONO (-6705 2750);
FORCEPROP 2 LAST CDS_LIB standard
J 0
(-6450 2750);
DISPLAY INVISIBLE (-6450 2750);
FORCEPROP 1 LAST OFFPAGE TRUE
J 2
(-6775 2625);
DISPLAY 0.872340 (-6775 2625);
PAINT GREEN (-6775 2625);
DISPLAY INVISIBLE (-6775 2625);
FORCEPROP 1 LAST COMMENT_BODY TRUE
J 2
(-6405 2655);
DISPLAY 0.872340 (-6405 2655);
PAINT GREEN (-6405 2655);
DISPLAY INVISIBLE (-6405 2655);
FORCEPROP 2 LAST PATH I306
J 0
(-6700 2800);
DISPLAY 1.021277 (-6700 2800);
DISPLAY INVISIBLE (-6700 2800);
FORCEADD OFFPAGE..1
(-6450 2650);
FORCEPROP 2 LAST $XR0 106 
J 0
(-6732 2650);
DISPLAY 0.638298 (-6732 2650);
PAINT MONO (-6732 2650);
FORCEPROP 2 LAST CDS_LIB standard
J 0
(-6450 2650);
DISPLAY INVISIBLE (-6450 2650);
FORCEPROP 1 LAST OFFPAGE TRUE
J 0
(-6125 2525);
DISPLAY 0.872340 (-6125 2525);
PAINT GREEN (-6125 2525);
DISPLAY INVISIBLE (-6125 2525);
FORCEPROP 1 LAST COMMENT_BODY TRUE
J 0
(-6325 2550);
DISPLAY 0.872340 (-6325 2550);
PAINT GREEN (-6325 2550);
DISPLAY INVISIBLE (-6325 2550);
FORCEPROP 2 LAST PATH I307
J 0
(-6725 2700);
DISPLAY 1.021277 (-6725 2700);
DISPLAY INVISIBLE (-6725 2700);
FORCEADD OFFPAGE..2
R 2
(-6450 2800);
FORCEPROP 2 LAST $XR0 106 
J 0
(-6705 2800);
DISPLAY 0.638298 (-6705 2800);
PAINT MONO (-6705 2800);
FORCEPROP 2 LAST CDS_LIB standard
J 0
(-6450 2800);
DISPLAY INVISIBLE (-6450 2800);
FORCEPROP 1 LAST OFFPAGE TRUE
J 2
(-6775 2675);
DISPLAY 0.872340 (-6775 2675);
PAINT GREEN (-6775 2675);
DISPLAY INVISIBLE (-6775 2675);
FORCEPROP 1 LAST COMMENT_BODY TRUE
J 2
(-6405 2705);
DISPLAY 0.872340 (-6405 2705);
PAINT GREEN (-6405 2705);
DISPLAY INVISIBLE (-6405 2705);
FORCEPROP 2 LAST PATH I308
J 0
(-6700 2850);
DISPLAY 1.021277 (-6700 2850);
DISPLAY INVISIBLE (-6700 2850);
FORCEADD OFFPAGE..5
(-6450 2550);
FORCEPROP 2 LAST $XR0 106 
J 0
(-6705 2550);
DISPLAY 0.638298 (-6705 2550);
PAINT MONO (-6705 2550);
FORCEPROP 2 LAST CDS_LIB mstr_standard
J 0
(-6450 2550);
DISPLAY INVISIBLE (-6450 2550);
FORCEPROP 1 LAST OFFPAGE TRUE
J 0
(-6125 2425);
DISPLAY 0.872340 (-6125 2425);
PAINT GREEN (-6125 2425);
DISPLAY INVISIBLE (-6125 2425);
FORCEPROP 1 LAST COMMENT_BODY TRUE
J 0
(-6350 2475);
DISPLAY 0.872340 (-6350 2475);
PAINT GREEN (-6350 2475);
DISPLAY INVISIBLE (-6350 2475);
FORCEPROP 2 LAST PATH I309
J 0
(-6700 2600);
DISPLAY 1.021277 (-6700 2600);
DISPLAY INVISIBLE (-6700 2600);
FORCEADD OFFPAGE..2
R 2
(-6450 2450);
FORCEPROP 2 LAST $XR0 106 
J 0
(-6705 2450);
DISPLAY 0.638298 (-6705 2450);
PAINT MONO (-6705 2450);
FORCEPROP 2 LAST CDS_LIB standard
J 0
(-6450 2450);
DISPLAY INVISIBLE (-6450 2450);
FORCEPROP 1 LAST OFFPAGE TRUE
J 2
(-6775 2325);
DISPLAY 0.872340 (-6775 2325);
PAINT GREEN (-6775 2325);
DISPLAY INVISIBLE (-6775 2325);
FORCEPROP 1 LAST COMMENT_BODY TRUE
J 2
(-6405 2355);
DISPLAY 0.872340 (-6405 2355);
PAINT GREEN (-6405 2355);
DISPLAY INVISIBLE (-6405 2355);
FORCEPROP 2 LAST PATH I310
J 0
(-6700 2500);
DISPLAY 1.021277 (-6700 2500);
DISPLAY INVISIBLE (-6700 2500);
FORCEADD OFFPAGE..2
R 2
(-6450 2400);
FORCEPROP 2 LAST $XR0 106 
J 0
(-6705 2400);
DISPLAY 0.638298 (-6705 2400);
PAINT MONO (-6705 2400);
FORCEPROP 2 LAST CDS_LIB standard
J 0
(-6450 2400);
DISPLAY INVISIBLE (-6450 2400);
FORCEPROP 1 LAST OFFPAGE TRUE
J 2
(-6775 2275);
DISPLAY 0.872340 (-6775 2275);
PAINT GREEN (-6775 2275);
DISPLAY INVISIBLE (-6775 2275);
FORCEPROP 1 LAST COMMENT_BODY TRUE
J 2
(-6405 2305);
DISPLAY 0.872340 (-6405 2305);
PAINT GREEN (-6405 2305);
DISPLAY INVISIBLE (-6405 2305);
FORCEPROP 2 LAST PATH I311
J 0
(-6700 2450);
DISPLAY 1.021277 (-6700 2450);
DISPLAY INVISIBLE (-6700 2450);
FORCEADD OFFPAGE..1
(-6450 2300);
FORCEPROP 2 LAST $XR0 106 
J 0
(-6732 2300);
DISPLAY 0.638298 (-6732 2300);
PAINT MONO (-6732 2300);
FORCEPROP 2 LAST CDS_LIB standard
J 0
(-6450 2300);
DISPLAY INVISIBLE (-6450 2300);
FORCEPROP 1 LAST OFFPAGE TRUE
J 0
(-6125 2175);
DISPLAY 0.872340 (-6125 2175);
PAINT GREEN (-6125 2175);
DISPLAY INVISIBLE (-6125 2175);
FORCEPROP 1 LAST COMMENT_BODY TRUE
J 0
(-6325 2200);
DISPLAY 0.872340 (-6325 2200);
PAINT GREEN (-6325 2200);
DISPLAY INVISIBLE (-6325 2200);
FORCEPROP 2 LAST PATH I312
J 0
(-6725 2350);
DISPLAY 1.021277 (-6725 2350);
DISPLAY INVISIBLE (-6725 2350);
FORCEADD OFFPAGE..5
(-6450 2200);
FORCEPROP 2 LAST $XR0 106 
J 0
(-6705 2200);
DISPLAY 0.638298 (-6705 2200);
PAINT MONO (-6705 2200);
FORCEPROP 2 LAST CDS_LIB standard
J 0
(-6450 2200);
DISPLAY INVISIBLE (-6450 2200);
FORCEPROP 1 LAST OFFPAGE TRUE
J 0
(-6125 2075);
DISPLAY 0.872340 (-6125 2075);
PAINT GREEN (-6125 2075);
DISPLAY INVISIBLE (-6125 2075);
FORCEPROP 1 LAST COMMENT_BODY TRUE
J 0
(-6350 2125);
DISPLAY 0.872340 (-6350 2125);
PAINT GREEN (-6350 2125);
DISPLAY INVISIBLE (-6350 2125);
FORCEPROP 2 LAST PATH I313
J 0
(-6700 2250);
DISPLAY 1.021277 (-6700 2250);
DISPLAY INVISIBLE (-6700 2250);
FORCEADD Q_RES..1
(-6525 2100);
FORCEPROP 1 LAST LOCATION R508
J 0
(-6850 2100);
DISPLAY 0.489362 (-6850 2100);
PAINT SKYBLUE (-6850 2100);
FORCEPROP 0 LAST $SEC 1
J 0
(-6700 2150);
DISPLAY 0.680851 (-6700 2150);
PAINT MONO (-6700 2150);
DISPLAY INVISIBLE (-6700 2150);
FORCEPROP 0 LAST CDS_SEC 1
J 0
(-6700 2150);
DISPLAY 1.021277 (-6700 2150);
DISPLAY INVISIBLE (-6700 2150);
FORCEPROP 1 LASTPIN (-6625 2100) $PN 1
J 0
(-6613 2112);
DISPLAY 0.489362 (-6613 2112);
PAINT MONO (-6613 2112);
FORCEPROP 1 LASTPIN (-6425 2100) $PN 2
J 0
(-6463 2112);
DISPLAY 0.489362 (-6463 2112);
PAINT MONO (-6463 2112);
FORCEPROP 1 LAST PACK_TYPE 0402LF
J 0
(-6850 2075);
DISPLAY 0.489362 (-6850 2075);
PAINT SKYBLUE (-6850 2075);
FORCEPROP 1 LAST TOLERANCE 1%
J 0
(-6250 2100);
DISPLAY 0.489362 (-6250 2100);
PAINT SKYBLUE (-6250 2100);
FORCEPROP 1 LAST VALUE 15
J 2
(-6200 2100);
DISPLAY 0.489362 (-6200 2100);
PAINT SKYBLUE (-6200 2100);
FORCEPROP 1 LAST MATERIAL CHIP
J 0
(-6650 2225);
DISPLAY 0.638298 (-6650 2225);
PAINT SKYBLUE (-6650 2225);
DISPLAY INVISIBLE (-6650 2225);
FORCEPROP 1 LAST WATTAGE 1/16W
J 2
(-6300 2225);
DISPLAY 0.638298 (-6300 2225);
PAINT SKYBLUE (-6300 2225);
DISPLAY INVISIBLE (-6300 2225);
FORCEPROP 2 LAST CDS_LIB pure_quanta
J 0
(-6525 2100);
DISPLAY INVISIBLE (-6525 2100);
FORCEPROP 1 LAST PATH I314
J 0
(-6575 2250);
DISPLAY 0.978723 (-6575 2250);
PAINT WHITE (-6575 2250);
DISPLAY INVISIBLE (-6575 2250);
FORCEPROP 1 LAST PART_NUMBER CS01502FB03
J 0
(-6425 2075);
DISPLAY 0.489362 (-6425 2075);
PAINT SKYBLUE (-6425 2075);
DISPLAY INVISIBLE (-6425 2075);
FORCEADD OFFPAGE..1
(-7400 2100);
FORCEPROP 2 LAST $XR0 106 
J 0
(-7652 2100);
DISPLAY 0.638298 (-7652 2100);
PAINT MONO (-7652 2100);
FORCEPROP 2 LAST CDS_LIB mstr_standard
J 0
(-7400 2100);
DISPLAY INVISIBLE (-7400 2100);
FORCEPROP 1 LAST OFFPAGE TRUE
J 0
(-7075 1975);
DISPLAY 0.872340 (-7075 1975);
PAINT GREEN (-7075 1975);
DISPLAY INVISIBLE (-7075 1975);
FORCEPROP 1 LAST COMMENT_BODY TRUE
J 0
(-7275 2000);
DISPLAY 0.872340 (-7275 2000);
PAINT GREEN (-7275 2000);
DISPLAY INVISIBLE (-7275 2000);
FORCEPROP 2 LAST PATH I315
J 0
(-7650 2150);
DISPLAY 1.021277 (-7650 2150);
DISPLAY INVISIBLE (-7650 2150);
FORCEADD OFFPAGE..5
(-6450 2000);
FORCEPROP 2 LAST $XR0 106 
J 0
(-6705 2000);
DISPLAY 0.638298 (-6705 2000);
PAINT MONO (-6705 2000);
FORCEPROP 2 LAST CDS_LIB standard
J 0
(-6450 2000);
DISPLAY INVISIBLE (-6450 2000);
FORCEPROP 1 LAST OFFPAGE TRUE
J 0
(-6125 1875);
DISPLAY 0.872340 (-6125 1875);
PAINT GREEN (-6125 1875);
DISPLAY INVISIBLE (-6125 1875);
FORCEPROP 1 LAST COMMENT_BODY TRUE
J 0
(-6350 1925);
DISPLAY 0.872340 (-6350 1925);
PAINT GREEN (-6350 1925);
DISPLAY INVISIBLE (-6350 1925);
FORCEPROP 2 LAST PATH I316
J 0
(-6700 2050);
DISPLAY 1.021277 (-6700 2050);
DISPLAY INVISIBLE (-6700 2050);
FORCEADD CAD_NOTE..1
(-7550 2375);
FORCEPROP 0 LAST L1 R1984 PLACE CLOSE TO CPU < 25MM
J 0
(-7700 2250);
DISPLAY 0.617021 (-7700 2250);
PAINT WHITE (-7700 2250);
FORCEPROP 2 LAST CDS_LIB pure_quanta_power
J 0
(-7550 2375);
DISPLAY INVISIBLE (-7550 2375);
FORCEPROP 1 LAST COMMENT_BODY TRUE
J 0
(-7525 2475);
DISPLAY 0.574468 (-7525 2475);
PAINT WHITE (-7525 2475);
DISPLAY INVISIBLE (-7525 2475);
FORCEADD QUANTA_TITLE_BLOCK_C..1
(0 0);
FORCEPROP 0 LAST CDS_CON_LAST_MODIFIED Thu Sep 14 16:11:57 2023
J 0
(-1885 15);
DISPLAY INVISIBLE (-1885 15);
FORCEPROP 1 LAST CUSTOM_TXT_CDS <CON_LAST_MODIFIED>
J 0
(-1885 15);
DISPLAY 0.978723 (-1885 15);
FORCEPROP 2 LAST CUSTOM_TXT_CDS <XR_PAGE_TITLE>
J 0
(-7890 5250);
DISPLAY 0.638298 (-7890 5250);
PAINT PINK (-7890 5250);
DISPLAY INVISIBLE (-7890 5250);
FORCEPROP 1 LAST CUSTOM_TXT_CDS <NAME_2>
J 0
(-3175 50);
FORCEPROP 1 LAST CUSTOM_TXT_CDS <NAME_1>
J 0
(-3175 175);
FORCEPROP 1 LAST CUSTOM_TXT_CDS <Q_NUMBER>
J 0
(-1403 103);
DISPLAY 1.212766 (-1403 103);
FORCEPROP 1 LAST CUSTOM_TXT_CDS <Q_PROJ>
J 0
(-2382 102);
DISPLAY 1.212766 (-2382 102);
FORCEPROP 1 LAST CUSTOM_TXT_CDS <Q_REV>
J 0
(-184 103);
DISPLAY 1.212766 (-184 103);
FORCEPROP 1 LAST CUSTOM_TXT_CDS <CON_PAGE_NUM> OF <CON_TOTAL_PAGES>
J 0
(-446 18);
DISPLAY 0.978723 (-446 18);
FORCEPROP 1 LAST Q_TITLE CPU1 DDR CHI
J 0
(-9366 26);
DISPLAY 2.446809 (-9366 26);
PAINT GREEN (-9366 26);
FORCEPROP 2 LAST PAGE_BORDER TRUE
J 0
(-7890 5250);
DISPLAY 0.638298 (-7890 5250);
PAINT PINK (-7890 5250);
DISPLAY INVISIBLE (-7890 5250);
FORCEPROP 1 LAST CDS_LMAN_SYM_OUTLINE -9475,6775,100,-125
J 0
(0 0);
DISPLAY 0.468085 (0 0);
PAINT GREEN (0 0);
DISPLAY INVISIBLE (0 0);
FORCEPROP 2 LAST CDS_LIB pure_quanta
J 0
(0 0);
DISPLAY INVISIBLE (0 0);
FORCEPROP 2 LAST CDS_XR_PAGE_TITLE CR-45 : @T6G_MB_LIB.T6G(SCH_1):PAGE45
J 0
(-7890 5250);
DISPLAY 0.638298 (-7890 5250);
PAINT PINK (-7890 5250);
DISPLAY INVISIBLE (-7890 5250);
FORCEPROP 1 LAST Q_DEPT BU9
J 1
(-3763 49);
DISPLAY 1.957447 (-3763 49);
PAINT GREEN (-3763 49);
DISPLAY INVISIBLE (-3763 49);
FORCEPROP 1 LAST COMMENT_BODY TRUE
J 0
(12 -13);
DISPLAY 0.978723 (12 -13);
PAINT GREEN (12 -13);
DISPLAY INVISIBLE (12 -13);
WIRE 17 -1 (-3175 5725)(-3175 5675);
WIRE 17 -1 (-3175 5775)(-3175 5725);
WIRE 17 -1 (-3175 5675)(-3175 5625);
WIRE 17 -1 (-3175 5625)(-3175 5525);
WIRE 17 -1 (-3175 5825)(-3175 5775);
WIRE 17 -1 (-3175 5875)(-3175 5825);
WIRE 17 -1 (-3175 5525)(-3175 5475);
WIRE 17 -1 (-3175 5475)(-3175 5425);
WIRE 17 -1 (-3175 5925)(-3175 5875);
WIRE 17 -1 (-3175 5975)(-3175 5925);
WIRE 17 -1 (-3175 5425)(-3175 5375);
WIRE 17 -1 (-3175 5375)(-3175 5325);
WIRE 17 -1 (-3175 5975)(-2550 5975);
FORCEPROP 2 LAST SIG_NAME M_I_CPU1_SA_DQ<31:0>
J 2
(-2610 5985);
DISPLAY 0.489362 (-2610 5985);
WIRE 17 -1 (-3175 5325)(-3175 5275);
WIRE 17 -1 (-3175 5275)(-3175 5225);
WIRE 17 -1 (-3175 5225)(-3175 5175);
WIRE 17 -1 (-3175 5075)(-3175 5175);
WIRE 17 -1 (-3175 5025)(-3175 5075);
WIRE 17 -1 (-3175 4975)(-3175 5025);
WIRE 17 -1 (-3175 4925)(-3175 4975);
WIRE 17 -1 (-3175 4925)(-3175 4875);
WIRE 17 -1 (-3175 4875)(-3175 4825);
WIRE 17 -1 (-3175 4825)(-3175 4775);
WIRE 17 -1 (-3175 4775)(-3175 4725);
WIRE 17 -1 (-3175 4725)(-3175 4625);
WIRE 17 -1 (-3175 4625)(-3175 4575);
WIRE 17 -1 (-3175 4575)(-3175 4525);
WIRE 17 -1 (-3175 4525)(-3175 4475);
WIRE 17 -1 (-3175 4425)(-3175 4475);
WIRE 17 -1 (-3175 4375)(-3175 4425);
WIRE 17 -1 (-3175 4325)(-3175 4375);
WIRE 17 -1 (-3175 4275)(-3175 4325);
WIRE 17 -1 (-3175 4175)(-2550 4175);
FORCEPROP 2 LAST SIG_NAME M_I_CPU1_SB_DQ<31:0>
J 2
(-2610 4185);
DISPLAY 0.489362 (-2610 4185);
WIRE 17 -1 (-3175 4175)(-3175 4125);
WIRE 17 -1 (-3175 3575)(-3175 3525);
WIRE 17 -1 (-3175 3625)(-3175 3575);
WIRE 17 -1 (-3175 3525)(-3175 3475);
WIRE 17 -1 (-3175 3475)(-3175 3425);
WIRE 17 -1 (-3175 3675)(-3175 3625);
WIRE 17 -1 (-3175 3725)(-3175 3675);
WIRE 17 -1 (-3175 3425)(-3175 3375);
WIRE 17 -1 (-3175 3275)(-3175 3375);
WIRE 17 -1 (-3175 3825)(-3175 3725);
WIRE 17 -1 (-3175 3875)(-3175 3825);
WIRE 17 -1 (-3175 3225)(-3175 3275);
WIRE 17 -1 (-3175 3175)(-3175 3225);
WIRE 17 -1 (-3175 3925)(-3175 3875);
WIRE 17 -1 (-3175 3975)(-3175 3925);
WIRE 17 -1 (-3175 3125)(-3175 3175);
WIRE 17 -1 (-3175 3125)(-3175 3075);
WIRE 17 -1 (-3175 4025)(-3175 3975);
WIRE 17 -1 (-3175 4075)(-3175 4025);
WIRE 17 -1 (-3175 3075)(-3175 3025);
WIRE 17 -1 (-3175 3025)(-3175 2975);
WIRE 17 -1 (-3175 4125)(-3175 4075);
WIRE 17 -1 (-3175 2975)(-3175 2925);
WIRE 17 -1 (-3175 2925)(-3175 2825);
WIRE 17 -1 (-3175 2825)(-3175 2775);
WIRE 17 -1 (-3175 2775)(-3175 2725);
WIRE 17 -1 (-3175 2725)(-3175 2675);
WIRE 17 -1 (-3175 2625)(-3175 2675);
WIRE 17 -1 (-3175 2575)(-3175 2625);
WIRE 17 -1 (-3175 2525)(-3175 2575);
WIRE 17 -1 (-3175 2475)(-3175 2525);
WIRE 17 -1 (-3175 2375)(-3175 2400);
WIRE 17 -1 (-3175 2375)(-3175 2325);
WIRE 17 -1 (-3175 2400)(-2675 2400);
FORCEPROP 2 LAST SIG_NAME M_I_CPU1_SA_CB<7:0>
J 2
(-2675 2410);
DISPLAY 0.489362 (-2675 2410);
WIRE 17 -1 (-3175 2275)(-3175 2325);
WIRE 17 -1 (-3175 2275)(-3175 2225);
WIRE 17 -1 (-3175 2175)(-3175 2225);
WIRE 17 -1 (-3175 2125)(-3175 2175);
WIRE 17 -1 (-3175 2075)(-3175 2125);
WIRE 17 -1 (-3175 2025)(-3175 2075);
WIRE 17 -1 (-3175 1825)(-3175 1775);
WIRE 17 -1 (-3175 1825)(-3175 1875);
WIRE 17 -1 (-3175 1725)(-3175 1775);
WIRE 17 -1 (-3175 1675)(-3175 1725);
WIRE 17 -1 (-3175 1925)(-3175 1875);
WIRE 17 -1 (-3175 1925)(-3175 1950);
WIRE 17 -1 (-3175 1625)(-3175 1675);
WIRE 17 -1 (-3175 1575)(-3175 1625);
WIRE 17 -1 (-3175 1950)(-2675 1950);
FORCEPROP 2 LAST SIG_NAME M_I_CPU1_SB_CB<7:0>
J 2
(-2675 1960);
DISPLAY 0.489362 (-2675 1960);
WIRE 17 -1 (-5700 5975)(-5700 5875);
WIRE 17 -1 (-5700 5975)(-6500 5975);
FORCEPROP 2 LAST SIG_NAME M_I_CPU1_SA_DQS_DP<9:0>
J 2
(-5935 5985);
DISPLAY 0.489362 (-5935 5985);
WIRE 17 -1 (-5700 5875)(-5700 5775);
WIRE 17 -1 (-5700 5775)(-5700 5675);
WIRE 17 -1 (-5700 5675)(-5700 5575);
WIRE 17 -1 (-5700 5475)(-5700 5575);
WIRE 17 -1 (-5700 5375)(-5700 5475);
WIRE 17 -1 (-5700 5275)(-5700 5375);
WIRE 17 -1 (-5700 5275)(-5700 5175);
WIRE 17 -1 (-5700 5175)(-5700 5075);
WIRE 17 -1 (-5900 5425)(-5900 5525);
WIRE 17 -1 (-5900 5325)(-5900 5425);
WIRE 17 -1 (-5900 5625)(-5900 5525);
WIRE 17 -1 (-5900 5725)(-5900 5625);
WIRE 17 -1 (-5900 5225)(-5900 5325);
WIRE 17 -1 (-5900 5225)(-5900 5125);
WIRE 17 -1 (-5900 5825)(-5900 5725);
WIRE 17 -1 (-5900 5925)(-5900 5825);
FORCEPROP 2 LAST SIG_NAME M_I_CPU1_SA_DQS_DN<9:0>
J 2
(-5935 5935);
DISPLAY 0.489362 (-5935 5935);
WIRE 17 -1 (-5900 5125)(-5900 5025);
WIRE 17 -1 (-5700 4925)(-5700 4825);
WIRE 17 -1 (-5700 4925)(-6500 4925);
FORCEPROP 2 LAST SIG_NAME M_I_CPU1_SB_DQS_DP<9:0>
J 2
(-5935 4935);
DISPLAY 0.489362 (-5935 4935);
WIRE 17 -1 (-5700 4825)(-5700 4725);
WIRE 17 -1 (-5700 4725)(-5700 4625);
WIRE 17 -1 (-5700 4625)(-5700 4525);
WIRE 17 -1 (-5700 4425)(-5700 4525);
WIRE 17 -1 (-5700 4325)(-5700 4425);
WIRE 17 -1 (-5700 4225)(-5700 4325);
WIRE 17 -1 (-5700 4225)(-5700 4125);
WIRE 17 -1 (-5700 4125)(-5700 4025);
WIRE 17 -1 (-5900 4875)(-5900 4775);
FORCEPROP 2 LAST SIG_NAME M_I_CPU1_SB_DQS_DN<9:0>
J 2
(-5935 4885);
DISPLAY 0.489362 (-5935 4885);
WIRE 17 -1 (-5900 4775)(-5900 4675);
WIRE 17 -1 (-5900 4675)(-5900 4575);
WIRE 17 -1 (-5900 4575)(-5900 4475);
WIRE 17 -1 (-5900 4375)(-5900 4475);
WIRE 17 -1 (-5900 4275)(-5900 4375);
WIRE 17 -1 (-5900 4175)(-5900 4275);
WIRE 17 -1 (-5900 4175)(-5900 4075);
WIRE 17 -1 (-5900 4075)(-5900 3975);
WIRE 17 -1 (-5900 3775)(-5900 3825);
WIRE 17 -1 (-5900 3725)(-5900 3775);
WIRE 17 -1 (-5900 3825)(-6400 3825);
FORCEPROP 2 LAST SIG_NAME M_I_CPU1_SA_CA<6:0>
J 0
(-6400 3835);
DISPLAY 0.489362 (-6400 3835);
WIRE 17 -1 (-5900 3375)(-5900 3425);
WIRE 17 -1 (-5900 3325)(-5900 3375);
WIRE 17 -1 (-5900 3425)(-6400 3425);
FORCEPROP 2 LAST SIG_NAME M_I_CPU1_SB_CA<6:0>
J 0
(-6400 3435);
DISPLAY 0.489362 (-6400 3435);
WIRE 17 -1 (-5900 3675)(-5900 3725);
WIRE 17 -1 (-5900 3275)(-5900 3325);
WIRE 17 -1 (-5900 3625)(-5900 3675);
WIRE 17 -1 (-5900 3575)(-5900 3625);
WIRE 17 -1 (-5900 3525)(-5900 3575);
WIRE 17 -1 (-5900 3225)(-5900 3275);
WIRE 17 -1 (-5900 3175)(-5900 3225);
WIRE 17 -1 (-5900 3125)(-5900 3175);
WIRE 17 -1 (-5900 5925)(-6500 5925);
WIRE 17 -1 (-5900 4875)(-6500 4875);
WIRE 16 -1 (-7350 2100)(-6625 2100);
FORCEPROP 2 LAST SIG_NAME M_I_CPU1_ALERT_N
J 0
(-7310 2110);
DISPLAY 0.489362 (-7310 2110);
WIRE 16 -1 (-6425 2100)(-5300 2100);
FORCEPROP 2 LAST SIG_NAME M_I_CPU1_ALERT_R_N
J 0
(-6135 2110);
DISPLAY 0.489362 (-6135 2110);
FORCEPROP 2 LASTPROP $XRERR UNIQUE?
J 0
(-6375 2110);
DISPLAY 0.638298 (-6375 2110);
PAINT MONO (-6375 2110);
DISPLAY INVISIBLE (-6375 2110);
WIRE 16 -1 (-6400 1150)(-5300 1150);
FORCEPROP 2 LAST SIG_NAME TP_M_I_CPU1_SA_TEST39I
J 0
(-6385 1160);
DISPLAY 0.489362 (-6385 1160);
FORCEPROP 2 LASTPROP $XRERR UNIQUE?
J 0
(-6640 1150);
DISPLAY 0.638298 (-6640 1150);
PAINT MONO (-6640 1150);
DISPLAY INVISIBLE (-6640 1150);
WIRE 16 -1 (-6400 2950)(-5300 2950);
FORCEPROP 2 LAST SIG_NAME M_I_CPU1_CLK_DP<0>
J 0
(-6400 2960);
DISPLAY 0.489362 (-6400 2960);
WIRE 16 -1 (-6400 2900)(-5300 2900);
FORCEPROP 2 LAST SIG_NAME M_I_CPU1_CLK_DN<0>
J 0
(-6400 2910);
DISPLAY 0.489362 (-6400 2910);
WIRE 16 -1 (-6400 2750)(-5300 2750);
FORCEPROP 2 LAST SIG_NAME M_I_CPU1_SA_CS_N<1>
J 0
(-6400 2760);
DISPLAY 0.489362 (-6400 2760);
WIRE 16 -1 (-6400 2650)(-5300 2650);
FORCEPROP 2 LAST SIG_NAME M_I_CPU1_SA_RSP<0>
J 0
(-6400 2660);
DISPLAY 0.489362 (-6400 2660);
WIRE 16 -1 (-6400 2800)(-5300 2800);
FORCEPROP 2 LAST SIG_NAME M_I_CPU1_SA_CS_N<0>
J 0
(-6400 2810);
DISPLAY 0.489362 (-6400 2810);
WIRE 16 -1 (-6400 2550)(-5300 2550);
FORCEPROP 2 LAST SIG_NAME M_I_CPU1_SA_PAR
J 0
(-6400 2560);
DISPLAY 0.489362 (-6400 2560);
WIRE 16 -1 (-6400 2450)(-5300 2450);
FORCEPROP 2 LAST SIG_NAME M_I_CPU1_SB_CS_N<0>
J 0
(-6400 2460);
DISPLAY 0.489362 (-6400 2460);
WIRE 16 -1 (-6400 2400)(-5300 2400);
FORCEPROP 2 LAST SIG_NAME M_I_CPU1_SB_CS_N<1>
J 0
(-6400 2410);
DISPLAY 0.489362 (-6400 2410);
WIRE 16 -1 (-6400 2300)(-5300 2300);
FORCEPROP 2 LAST SIG_NAME M_I_CPU1_SB_RSP<0>
J 0
(-6400 2310);
DISPLAY 0.489362 (-6400 2310);
WIRE 16 -1 (-6400 2200)(-5300 2200);
FORCEPROP 2 LAST SIG_NAME M_I_CPU1_SB_PAR
J 0
(-6400 2210);
DISPLAY 0.489362 (-6400 2210);
WIRE 16 -1 (-6400 2000)(-5300 2000);
FORCEPROP 2 LAST SIG_NAME M_I_CPU1_RESET_N
J 0
(-6400 2010);
DISPLAY 0.489362 (-6400 2010);
WIRE 16 -1 (-5800 3950)(-5300 3950);
WIRE 16 -1 (-5800 4050)(-5300 4050);
WIRE 16 -1 (-5800 3100)(-5300 3100);
WIRE 16 -1 (-5800 3500)(-5300 3500);
WIRE 16 -1 (-5800 3150)(-5300 3150);
WIRE 16 -1 (-5800 3550)(-5300 3550);
WIRE 16 -1 (-5800 3200)(-5300 3200);
WIRE 16 -1 (-5800 3600)(-5300 3600);
WIRE 16 -1 (-5800 3250)(-5300 3250);
WIRE 16 -1 (-5800 3650)(-5300 3650);
WIRE 16 -1 (-5800 3300)(-5300 3300);
WIRE 16 -1 (-5800 3700)(-5300 3700);
WIRE 16 -1 (-5800 3350)(-5300 3350);
WIRE 16 -1 (-5800 3750)(-5300 3750);
WIRE 16 -1 (-5800 3400)(-5300 3400);
WIRE 16 -1 (-5800 3800)(-5300 3800);
WIRE 16 -1 (-5600 4000)(-5300 4000);
WIRE 16 -1 (-5800 4150)(-5300 4150);
WIRE 16 -1 (-5800 4250)(-5300 4250);
WIRE 16 -1 (-5800 4350)(-5300 4350);
WIRE 16 -1 (-5800 4450)(-5300 4450);
WIRE 16 -1 (-5800 5000)(-5300 5000);
WIRE 16 -1 (-5800 4550)(-5300 4550);
WIRE 16 -1 (-5800 5100)(-5300 5100);
WIRE 16 -1 (-5800 4650)(-5300 4650);
WIRE 16 -1 (-5800 4750)(-5300 4750);
WIRE 16 -1 (-5800 4850)(-5300 4850);
WIRE 16 -1 (-5600 4100)(-5300 4100);
WIRE 16 -1 (-5600 4200)(-5300 4200);
WIRE 16 -1 (-5600 4300)(-5300 4300);
WIRE 16 -1 (-5600 4400)(-5300 4400);
WIRE 16 -1 (-5600 4500)(-5300 4500);
WIRE 16 -1 (-5600 4600)(-5300 4600);
WIRE 16 -1 (-5600 5050)(-5300 5050);
WIRE 16 -1 (-5600 4700)(-5300 4700);
WIRE 16 -1 (-5600 4800)(-5300 4800);
WIRE 16 -1 (-5600 4900)(-5300 4900);
WIRE 16 -1 (-5800 5500)(-5300 5500);
WIRE 16 -1 (-5800 5600)(-5300 5600);
WIRE 16 -1 (-5800 5700)(-5300 5700);
WIRE 16 -1 (-5800 5800)(-5300 5800);
WIRE 16 -1 (-5800 5900)(-5300 5900);
WIRE 16 -1 (-5800 5200)(-5300 5200);
WIRE 16 -1 (-5800 5300)(-5300 5300);
WIRE 16 -1 (-5800 5400)(-5300 5400);
WIRE 16 -1 (-5600 5150)(-5300 5150);
WIRE 16 -1 (-5600 5250)(-5300 5250);
WIRE 16 -1 (-5600 5350)(-5300 5350);
WIRE 16 -1 (-5600 5450)(-5300 5450);
WIRE 16 -1 (-5600 5550)(-5300 5550);
WIRE 16 -1 (-5600 5950)(-5300 5950);
WIRE 16 -1 (-5600 5650)(-5300 5650);
WIRE 16 -1 (-5600 5750)(-5300 5750);
WIRE 16 -1 (-5600 5850)(-5300 5850);
WIRE 16 -1 (-3700 1800)(-3275 1800);
WIRE 16 -1 (-3700 2000)(-3275 2000);
WIRE 16 -1 (-3700 1850)(-3275 1850);
WIRE 16 -1 (-3700 1900)(-3275 1900);
WIRE 16 -1 (-3700 1550)(-3275 1550);
WIRE 16 -1 (-3700 1600)(-3275 1600);
WIRE 16 -1 (-3700 1650)(-3275 1650);
WIRE 16 -1 (-3700 1700)(-3275 1700);
WIRE 16 -1 (-3700 1750)(-3275 1750);
WIRE 16 -1 (-3700 2950)(-3275 2950);
WIRE 16 -1 (-3700 3000)(-3275 3000);
WIRE 16 -1 (-3700 2050)(-3275 2050);
WIRE 16 -1 (-3700 3050)(-3275 3050);
WIRE 16 -1 (-3700 2450)(-3275 2450);
WIRE 16 -1 (-3700 2100)(-3275 2100);
WIRE 16 -1 (-3700 2500)(-3275 2500);
WIRE 16 -1 (-3700 2150)(-3275 2150);
WIRE 16 -1 (-3700 2200)(-3275 2200);
WIRE 16 -1 (-3700 2250)(-3275 2250);
WIRE 16 -1 (-3700 2300)(-3275 2300);
WIRE 16 -1 (-3700 2350)(-3275 2350);
WIRE 16 -1 (-3700 2550)(-3275 2550);
WIRE 16 -1 (-3700 2600)(-3275 2600);
WIRE 16 -1 (-3700 2650)(-3275 2650);
WIRE 16 -1 (-3700 2700)(-3275 2700);
WIRE 16 -1 (-3700 2750)(-3275 2750);
WIRE 16 -1 (-3700 2800)(-3275 2800);
WIRE 16 -1 (-3700 2900)(-3275 2900);
WIRE 16 -1 (-3700 3900)(-3275 3900);
WIRE 16 -1 (-3700 3550)(-3275 3550);
WIRE 16 -1 (-3700 3950)(-3275 3950);
WIRE 16 -1 (-3700 3600)(-3275 3600);
WIRE 16 -1 (-3700 4000)(-3275 4000);
WIRE 16 -1 (-3700 4050)(-3275 4050);
WIRE 16 -1 (-3700 3100)(-3275 3100);
WIRE 16 -1 (-3700 3150)(-3275 3150);
WIRE 16 -1 (-3700 3200)(-3275 3200);
WIRE 16 -1 (-3700 3250)(-3275 3250);
WIRE 16 -1 (-3700 3650)(-3275 3650);
WIRE 16 -1 (-3700 3350)(-3275 3350);
WIRE 16 -1 (-3700 3700)(-3275 3700);
WIRE 16 -1 (-3700 3400)(-3275 3400);
WIRE 16 -1 (-3700 3800)(-3275 3800);
WIRE 16 -1 (-3700 3450)(-3275 3450);
WIRE 16 -1 (-3700 3850)(-3275 3850);
WIRE 16 -1 (-3700 3500)(-3275 3500);
WIRE 16 -1 (-3700 5000)(-3275 5000);
WIRE 16 -1 (-3700 4400)(-3275 4400);
WIRE 16 -1 (-3700 5050)(-3275 5050);
WIRE 16 -1 (-3700 4450)(-3275 4450);
WIRE 16 -1 (-3700 4500)(-3275 4500);
WIRE 16 -1 (-3700 4550)(-3275 4550);
WIRE 16 -1 (-3700 4600)(-3275 4600);
WIRE 16 -1 (-3700 4100)(-3275 4100);
WIRE 16 -1 (-3700 4700)(-3275 4700);
WIRE 16 -1 (-3700 4150)(-3275 4150);
WIRE 16 -1 (-3700 4750)(-3275 4750);
WIRE 16 -1 (-3700 4800)(-3275 4800);
WIRE 16 -1 (-3700 4850)(-3275 4850);
WIRE 16 -1 (-3700 4250)(-3275 4250);
WIRE 16 -1 (-3700 4300)(-3275 4300);
WIRE 16 -1 (-3700 4900)(-3275 4900);
WIRE 16 -1 (-3700 4950)(-3275 4950);
WIRE 16 -1 (-3700 4350)(-3275 4350);
WIRE 16 -1 (-3700 5700)(-3275 5700);
WIRE 16 -1 (-3700 5750)(-3275 5750);
WIRE 16 -1 (-3700 5800)(-3275 5800);
WIRE 16 -1 (-3700 5150)(-3275 5150);
WIRE 16 -1 (-3700 5850)(-3275 5850);
WIRE 16 -1 (-3700 5200)(-3275 5200);
WIRE 16 -1 (-3700 5900)(-3275 5900);
WIRE 16 -1 (-3700 5250)(-3275 5250);
WIRE 16 -1 (-3700 5950)(-3275 5950);
WIRE 16 -1 (-3700 5300)(-3275 5300);
WIRE 16 -1 (-3700 5350)(-3275 5350);
WIRE 16 -1 (-3700 5400)(-3275 5400);
WIRE 16 -1 (-3700 5450)(-3275 5450);
WIRE 16 -1 (-3700 5500)(-3275 5500);
WIRE 16 -1 (-3700 5600)(-3275 5600);
WIRE 16 -1 (-3700 5650)(-3275 5650);
QUIT
